FILE_TYPE = MACRO_DRAWING;
SET COLOR_WIRE YELLOW;
SET COLOR_PROP ORANGE;
SET COLOR_DOT WHITE;
SET COLOR_ARC YELLOW;
SET COLOR_BODY GREEN;
SET COLOR_NOTE PURPLE;
SET PROP_DISPLAY VALUE;
SET PAGE_NUMBER P76;
FORCEADD Q_CAP..1
(-3925 4025);
FORCEPROP 1 LAST PART_NUMBER CH647KMEA04
J 0
(-3875 3875);
DISPLAY 0.638298 (-3875 3875);
DISPLAY INVISIBLE (-3875 3875);
FORCEPROP 1 LAST TOLERANCE 20%
J 0
(-3875 3975);
DISPLAY 0.638298 (-3875 3975);
FORCEPROP 1 LAST VOLTAGE 4V
J 0
(-3875 4025);
DISPLAY 0.638298 (-3875 4025);
FORCEPROP 1 LAST PACK_TYPE C0805
J 0
(-3875 3825);
DISPLAY 0.638298 (-3875 3825);
FORCEPROP 1 LAST VALUE 47UF
J 0
(-3875 4075);
DISPLAY 0.638298 (-3875 4075);
FORCEPROP 1 LAST MATERIAL X6S
J 0
(-3875 3925);
DISPLAY 0.638298 (-3875 3925);
FORCEPROP 1 LAST $LOCATION C494
J 0
(-3875 4125);
DISPLAY 0.978723 (-3875 4125);
FORCEPROP 1 LASTPIN (-3925 4125) $PN 1
J 0
(-3915 4105);
DISPLAY 0.787234 (-3915 4105);
FORCEPROP 1 LASTPIN (-3925 3925) $PN 2
J 0
(-3915 3905);
DISPLAY 0.787234 (-3915 3905);
FORCEPROP 2 LAST CDS_LIB pure_quanta
J 0
(-3925 4025);
PAINT MONO (-3925 4025);
DISPLAY INVISIBLE (-3925 4025);
FORCEPROP 2 LAST CDS_LOCATION C494
J 0
(-3875 4225);
DISPLAY 1.021277 (-3875 4225);
DISPLAY INVISIBLE (-3875 4225);
FORCEPROP 2 LAST $SEC 1
J 0
(-3875 4225);
DISPLAY 0.680851 (-3875 4225);
PAINT MONO (-3875 4225);
DISPLAY INVISIBLE (-3875 4225);
FORCEPROP 2 LAST CDS_SEC 1
J 0
(-3875 4225);
DISPLAY 1.021277 (-3875 4225);
DISPLAY INVISIBLE (-3875 4225);
FORCEPROP 1 LAST PATH I1
J 0
(-3875 4175);
DISPLAY 0.978723 (-3875 4175);
PAINT WHITE (-3875 4175);
DISPLAY INVISIBLE (-3875 4175);
FORCEADD Q_CAP..1
(-3475 6100);
FORCEPROP 1 LAST PART_NUMBER CH647KMEA04
J 0
(-3425 5950);
DISPLAY 0.638298 (-3425 5950);
DISPLAY INVISIBLE (-3425 5950);
FORCEPROP 1 LAST VALUE 47UF
J 0
(-3425 6150);
DISPLAY 0.638298 (-3425 6150);
FORCEPROP 1 LAST TOLERANCE 20%
J 0
(-3425 6050);
DISPLAY 0.638298 (-3425 6050);
FORCEPROP 1 LAST VOLTAGE 4V
J 0
(-3425 6100);
DISPLAY 0.638298 (-3425 6100);
FORCEPROP 1 LAST PACK_TYPE C0805
J 0
(-3425 5900);
DISPLAY 0.638298 (-3425 5900);
FORCEPROP 1 LAST MATERIAL X6S
J 0
(-3425 6000);
DISPLAY 0.638298 (-3425 6000);
FORCEPROP 1 LAST $LOCATION C504
J 0
(-3425 6200);
DISPLAY 0.978723 (-3425 6200);
FORCEPROP 1 LASTPIN (-3475 6200) $PN 1
J 0
(-3465 6180);
DISPLAY 0.787234 (-3465 6180);
FORCEPROP 1 LASTPIN (-3475 6000) $PN 2
J 0
(-3465 5980);
DISPLAY 0.787234 (-3465 5980);
FORCEPROP 2 LAST CDS_LIB pure_quanta
J 0
(-3475 6100);
PAINT MONO (-3475 6100);
DISPLAY INVISIBLE (-3475 6100);
FORCEPROP 2 LAST CDS_LOCATION C504
J 0
(-3425 6300);
DISPLAY 1.021277 (-3425 6300);
DISPLAY INVISIBLE (-3425 6300);
FORCEPROP 2 LAST $SEC 1
J 0
(-3425 6300);
DISPLAY 0.680851 (-3425 6300);
PAINT MONO (-3425 6300);
DISPLAY INVISIBLE (-3425 6300);
FORCEPROP 2 LAST CDS_SEC 1
J 0
(-3425 6300);
DISPLAY 1.021277 (-3425 6300);
DISPLAY INVISIBLE (-3425 6300);
FORCEPROP 1 LAST PATH I10
J 0
(-3425 6250);
DISPLAY 0.978723 (-3425 6250);
PAINT WHITE (-3425 6250);
DISPLAY INVISIBLE (-3425 6250);
FORCEADD Q_CAP..1
(-3025 6100);
FORCEPROP 1 LAST PART_NUMBER CH647KMEA04
J 0
(-2975 5950);
DISPLAY 0.638298 (-2975 5950);
DISPLAY INVISIBLE (-2975 5950);
FORCEPROP 1 LAST TOLERANCE 20%
J 0
(-2975 6050);
DISPLAY 0.638298 (-2975 6050);
FORCEPROP 1 LAST VOLTAGE 4V
J 0
(-2975 6100);
DISPLAY 0.638298 (-2975 6100);
FORCEPROP 1 LAST PACK_TYPE C0805
J 0
(-2975 5900);
DISPLAY 0.638298 (-2975 5900);
FORCEPROP 1 LAST MATERIAL X6S
J 0
(-2975 6000);
DISPLAY 0.638298 (-2975 6000);
FORCEPROP 1 LAST VALUE 47UF
J 0
(-2975 6150);
DISPLAY 0.638298 (-2975 6150);
FORCEPROP 1 LAST $LOCATION C508
J 0
(-2975 6200);
DISPLAY 0.978723 (-2975 6200);
FORCEPROP 1 LASTPIN (-3025 6200) $PN 1
J 0
(-3015 6180);
DISPLAY 0.787234 (-3015 6180);
FORCEPROP 1 LASTPIN (-3025 6000) $PN 2
J 0
(-3015 5980);
DISPLAY 0.787234 (-3015 5980);
FORCEPROP 2 LAST CDS_LIB pure_quanta
J 0
(-3025 6100);
PAINT MONO (-3025 6100);
DISPLAY INVISIBLE (-3025 6100);
FORCEPROP 2 LAST CDS_LOCATION C508
J 0
(-2975 6300);
DISPLAY 1.021277 (-2975 6300);
DISPLAY INVISIBLE (-2975 6300);
FORCEPROP 2 LAST $SEC 1
J 0
(-2975 6300);
DISPLAY 0.680851 (-2975 6300);
PAINT MONO (-2975 6300);
DISPLAY INVISIBLE (-2975 6300);
FORCEPROP 2 LAST CDS_SEC 1
J 0
(-2975 6300);
DISPLAY 1.021277 (-2975 6300);
DISPLAY INVISIBLE (-2975 6300);
FORCEPROP 1 LAST PATH I11
J 0
(-2975 6250);
DISPLAY 0.978723 (-2975 6250);
PAINT WHITE (-2975 6250);
DISPLAY INVISIBLE (-2975 6250);
FORCEADD UNIVERSAL_POWER..1
(-3925 6375);
FORCEPROP 3 LASTPIN (-3925 6325) SIG_NAME PVCCFA_EHV_CPU0\g
J 0
(-3915 6335);
DISPLAY 0.659574 (-3915 6335);
PAINT MONO (-3915 6335);
DISPLAY INVISIBLE (-3915 6335);
FORCEPROP 1 LAST HDL_POWER PVCCFA_EHV_CPU0
J 1
(-3650 6425);
DISPLAY 0.872340 (-3650 6425);
PAINT GREEN (-3650 6425);
FORCEPROP 2 LAST CDS_LIB logical_power
J 0
(-3925 6375);
PAINT MONO (-3925 6375);
DISPLAY INVISIBLE (-3925 6375);
FORCEPROP 1 LAST PATH I12
J 0
(-3875 6400);
DISPLAY 0.872340 (-3875 6400);
PAINT AQUA (-3875 6400);
DISPLAY INVISIBLE (-3875 6400);
FORCEADD Q_CAP..1
(-3925 7100);
FORCEPROP 1 LAST PART_NUMBER CH647KMEA04
J 0
(-3875 6950);
DISPLAY 0.638298 (-3875 6950);
DISPLAY INVISIBLE (-3875 6950);
FORCEPROP 1 LAST TOLERANCE 20%
J 0
(-3875 7050);
DISPLAY 0.638298 (-3875 7050);
FORCEPROP 1 LAST VOLTAGE 4V
J 0
(-3875 7100);
DISPLAY 0.638298 (-3875 7100);
FORCEPROP 1 LAST PACK_TYPE C0805
J 0
(-3875 6900);
DISPLAY 0.638298 (-3875 6900);
FORCEPROP 1 LAST VALUE 47UF
J 0
(-3875 7150);
DISPLAY 0.638298 (-3875 7150);
FORCEPROP 1 LAST MATERIAL X6S
J 0
(-3875 7000);
DISPLAY 0.638298 (-3875 7000);
FORCEPROP 1 LAST $LOCATION C1399
J 0
(-3875 7200);
DISPLAY 0.978723 (-3875 7200);
FORCEPROP 1 LASTPIN (-3925 7200) $PN 1
J 0
(-3915 7180);
DISPLAY 0.787234 (-3915 7180);
FORCEPROP 1 LASTPIN (-3925 7000) $PN 2
J 0
(-3915 6980);
DISPLAY 0.787234 (-3915 6980);
FORCEPROP 2 LAST CDS_LIB pure_quanta
J 0
(-3925 7100);
PAINT MONO (-3925 7100);
DISPLAY INVISIBLE (-3925 7100);
FORCEPROP 2 LAST CDS_LOCATION C1399
J 0
(-3875 7300);
DISPLAY 1.021277 (-3875 7300);
DISPLAY INVISIBLE (-3875 7300);
FORCEPROP 2 LAST $SEC 1
J 0
(-3875 7300);
DISPLAY 0.680851 (-3875 7300);
PAINT MONO (-3875 7300);
DISPLAY INVISIBLE (-3875 7300);
FORCEPROP 2 LAST CDS_SEC 1
J 0
(-3875 7300);
DISPLAY 1.021277 (-3875 7300);
DISPLAY INVISIBLE (-3875 7300);
FORCEPROP 1 LAST PATH I13
J 0
(-3875 7250);
DISPLAY 0.978723 (-3875 7250);
PAINT WHITE (-3875 7250);
DISPLAY INVISIBLE (-3875 7250);
FORCEADD Q_CAP..1
(-3475 7100);
FORCEPROP 1 LAST PART_NUMBER CH647KMEA04
J 0
(-3425 6950);
DISPLAY 0.638298 (-3425 6950);
DISPLAY INVISIBLE (-3425 6950);
FORCEPROP 1 LAST TOLERANCE 20%
J 0
(-3425 7050);
DISPLAY 0.638298 (-3425 7050);
FORCEPROP 1 LAST VOLTAGE 4V
J 0
(-3425 7100);
DISPLAY 0.638298 (-3425 7100);
FORCEPROP 1 LAST PACK_TYPE C0805
J 0
(-3425 6900);
DISPLAY 0.638298 (-3425 6900);
FORCEPROP 1 LAST VALUE 47UF
J 0
(-3425 7150);
DISPLAY 0.638298 (-3425 7150);
FORCEPROP 1 LAST MATERIAL X6S
J 0
(-3425 7000);
DISPLAY 0.638298 (-3425 7000);
FORCEPROP 1 LAST $LOCATION C1400
J 0
(-3425 7200);
DISPLAY 0.978723 (-3425 7200);
FORCEPROP 1 LASTPIN (-3475 7200) $PN 1
J 0
(-3465 7180);
DISPLAY 0.787234 (-3465 7180);
PAINT MONO (-3465 7180);
FORCEPROP 1 LASTPIN (-3475 7000) $PN 2
J 0
(-3465 6980);
DISPLAY 0.787234 (-3465 6980);
PAINT MONO (-3465 6980);
FORCEPROP 2 LAST CDS_LIB pure_quanta
J 0
(-3475 7100);
DISPLAY INVISIBLE (-3475 7100);
FORCEPROP 2 LAST CDS_LOCATION C1400
J 0
(-3425 7300);
DISPLAY 1.021277 (-3425 7300);
DISPLAY INVISIBLE (-3425 7300);
FORCEPROP 0 LAST $SEC 1
J 0
(-3425 7250);
DISPLAY 0.680851 (-3425 7250);
PAINT MONO (-3425 7250);
DISPLAY INVISIBLE (-3425 7250);
FORCEPROP 2 LAST CDS_SEC 1
J 0
(-3425 7300);
DISPLAY 1.021277 (-3425 7300);
DISPLAY INVISIBLE (-3425 7300);
FORCEPROP 1 LAST PATH I14
J 0
(-3425 7250);
DISPLAY 0.978723 (-3425 7250);
PAINT WHITE (-3425 7250);
DISPLAY INVISIBLE (-3425 7250);
FORCEADD UNIVERSAL_GND..1
(-3075 6750);
FORCEPROP 3 LASTPIN (-3075 6800) SIG_NAME GND\g
J 0
(-3065 6810);
DISPLAY 0.659574 (-3065 6810);
PAINT MONO (-3065 6810);
DISPLAY INVISIBLE (-3065 6810);
FORCEPROP 2 LAST CDS_LIB logical_power
J 0
(-3075 6750);
PAINT MONO (-3075 6750);
DISPLAY INVISIBLE (-3075 6750);
FORCEPROP 1 LAST HDL_POWER GND
J 1
(-3050 6675);
DISPLAY 0.872340 (-3050 6675);
PAINT GREEN (-3050 6675);
DISPLAY INVISIBLE (-3050 6675);
FORCEPROP 1 LAST PATH I15
J 0
(-3000 6750);
DISPLAY 0.872340 (-3000 6750);
PAINT AQUA (-3000 6750);
DISPLAY INVISIBLE (-3000 6750);
FORCEADD Q_CAP..1
(-3075 7100);
FORCEPROP 1 LAST PART_NUMBER CH622KMEB01
J 0
(-3025 6950);
DISPLAY 0.638298 (-3025 6950);
DISPLAY INVISIBLE (-3025 6950);
FORCEPROP 1 LAST TOLERANCE 20%
J 0
(-3025 7050);
DISPLAY 0.638298 (-3025 7050);
FORCEPROP 1 LAST MATERIAL X6S
J 0
(-3025 7000);
DISPLAY 0.638298 (-3025 7000);
FORCEPROP 1 LAST VOLTAGE 4V
J 0
(-3025 7100);
DISPLAY 0.638298 (-3025 7100);
FORCEPROP 1 LAST PACK_TYPE C0402
J 0
(-3025 6900);
DISPLAY 0.638298 (-3025 6900);
FORCEPROP 1 LAST VALUE 22UF
J 0
(-3025 7150);
DISPLAY 0.638298 (-3025 7150);
FORCEPROP 1 LAST $LOCATION C1362
J 0
(-3025 7200);
DISPLAY 0.787234 (-3025 7200);
FORCEPROP 1 LASTPIN (-3075 7200) $PN 1
J 0
(-3065 7180);
DISPLAY 0.787234 (-3065 7180);
PAINT MONO (-3065 7180);
FORCEPROP 1 LASTPIN (-3075 7000) $PN 2
J 0
(-3065 6980);
DISPLAY 0.787234 (-3065 6980);
PAINT MONO (-3065 6980);
FORCEPROP 2 LAST CDS_LIB pure_quanta
J 0
(-3075 7100);
DISPLAY INVISIBLE (-3075 7100);
FORCEPROP 0 LAST CDS_LOCATION C1362
J 0
(-3025 7250);
DISPLAY 1.021277 (-3025 7250);
DISPLAY INVISIBLE (-3025 7250);
FORCEPROP 0 LAST $SEC 1
J 0
(-3025 7250);
DISPLAY 0.680851 (-3025 7250);
PAINT MONO (-3025 7250);
DISPLAY INVISIBLE (-3025 7250);
FORCEPROP 0 LAST CDS_SEC 1
J 0
(-3025 7250);
DISPLAY 1.021277 (-3025 7250);
DISPLAY INVISIBLE (-3025 7250);
FORCEPROP 1 LAST PATH I16
J 0
(-3025 7250);
DISPLAY 0.978723 (-3025 7250);
PAINT WHITE (-3025 7250);
DISPLAY INVISIBLE (-3025 7250);
FORCEADD UNIVERSAL_POWER..1
(-3925 7375);
FORCEPROP 3 LASTPIN (-3925 7325) SIG_NAME PVNN_MAIN_CPU0\g
J 0
(-3915 7335);
DISPLAY 0.659574 (-3915 7335);
PAINT MONO (-3915 7335);
DISPLAY INVISIBLE (-3915 7335);
FORCEPROP 1 LAST HDL_POWER PVNN_MAIN_CPU0
J 1
(-3725 7425);
DISPLAY 0.872340 (-3725 7425);
PAINT GREEN (-3725 7425);
FORCEPROP 2 LAST CDS_LIB logical_power
J 0
(-3925 7375);
PAINT MONO (-3925 7375);
DISPLAY INVISIBLE (-3925 7375);
FORCEPROP 1 LAST PATH I17
J 0
(-3875 7400);
DISPLAY 0.872340 (-3875 7400);
PAINT AQUA (-3875 7400);
DISPLAY INVISIBLE (-3875 7400);
FORCEADD Q_CAP..1
(-3925 7950);
FORCEPROP 1 LAST PART_NUMBER CH647KMEA04
J 0
(-3875 7800);
DISPLAY 0.638298 (-3875 7800);
DISPLAY INVISIBLE (-3875 7800);
FORCEPROP 1 LAST VALUE 47UF
J 0
(-3875 8000);
DISPLAY 0.638298 (-3875 8000);
FORCEPROP 1 LAST TOLERANCE 20%
J 0
(-3875 7900);
DISPLAY 0.638298 (-3875 7900);
FORCEPROP 1 LAST VOLTAGE 4V
J 0
(-3875 7950);
DISPLAY 0.638298 (-3875 7950);
FORCEPROP 1 LAST PACK_TYPE C0805
J 0
(-3875 7750);
DISPLAY 0.638298 (-3875 7750);
FORCEPROP 1 LAST MATERIAL X6S
J 0
(-3875 7850);
DISPLAY 0.638298 (-3875 7850);
FORCEPROP 1 LAST $LOCATION C499
J 0
(-3875 8050);
DISPLAY 0.978723 (-3875 8050);
FORCEPROP 1 LASTPIN (-3925 8050) $PN 1
J 0
(-3915 8030);
DISPLAY 0.787234 (-3915 8030);
FORCEPROP 1 LASTPIN (-3925 7850) $PN 2
J 0
(-3915 7830);
DISPLAY 0.787234 (-3915 7830);
FORCEPROP 2 LAST CDS_LIB pure_quanta
J 0
(-3925 7950);
PAINT MONO (-3925 7950);
DISPLAY INVISIBLE (-3925 7950);
FORCEPROP 2 LAST CDS_LOCATION C499
J 0
(-3875 8150);
DISPLAY 1.021277 (-3875 8150);
DISPLAY INVISIBLE (-3875 8150);
FORCEPROP 2 LAST $SEC 1
J 0
(-3875 8150);
DISPLAY 0.680851 (-3875 8150);
PAINT MONO (-3875 8150);
DISPLAY INVISIBLE (-3875 8150);
FORCEPROP 2 LAST CDS_SEC 1
J 0
(-3875 8150);
DISPLAY 1.021277 (-3875 8150);
DISPLAY INVISIBLE (-3875 8150);
FORCEPROP 1 LAST PATH I18
J 0
(-3875 8100);
DISPLAY 0.978723 (-3875 8100);
PAINT WHITE (-3875 8100);
DISPLAY INVISIBLE (-3875 8100);
FORCEADD UNIVERSAL_POWER..1
(-3925 8225);
FORCEPROP 3 LASTPIN (-3925 8175) SIG_NAME PVCCD_HV_CPU0\g
J 0
(-3915 8185);
DISPLAY 0.659574 (-3915 8185);
PAINT MONO (-3915 8185);
DISPLAY INVISIBLE (-3915 8185);
FORCEPROP 1 LAST HDL_POWER PVCCD_HV_CPU0
J 1
(-3700 8275);
DISPLAY 0.872340 (-3700 8275);
PAINT GREEN (-3700 8275);
FORCEPROP 2 LAST CDS_LIB logical_power
J 0
(-3925 8225);
PAINT MONO (-3925 8225);
DISPLAY INVISIBLE (-3925 8225);
FORCEPROP 1 LAST PATH I19
J 0
(-3875 8250);
DISPLAY 0.872340 (-3875 8250);
PAINT AQUA (-3875 8250);
DISPLAY INVISIBLE (-3875 8250);
FORCEADD Q_CAP..1
(-3475 4025);
FORCEPROP 1 LAST PART_NUMBER CH647KMEA04
J 0
(-3425 3875);
DISPLAY 0.638298 (-3425 3875);
DISPLAY INVISIBLE (-3425 3875);
FORCEPROP 1 LAST TOLERANCE 20%
J 0
(-3425 3975);
DISPLAY 0.638298 (-3425 3975);
FORCEPROP 1 LAST VOLTAGE 4V
J 0
(-3425 4025);
DISPLAY 0.638298 (-3425 4025);
FORCEPROP 1 LAST PACK_TYPE C0805
J 0
(-3425 3825);
DISPLAY 0.638298 (-3425 3825);
FORCEPROP 1 LAST VALUE 47UF
J 0
(-3425 4075);
DISPLAY 0.638298 (-3425 4075);
FORCEPROP 1 LAST MATERIAL X6S
J 0
(-3425 3925);
DISPLAY 0.638298 (-3425 3925);
FORCEPROP 1 LAST $LOCATION C498
J 0
(-3425 4125);
DISPLAY 0.978723 (-3425 4125);
FORCEPROP 1 LASTPIN (-3475 4125) $PN 1
J 0
(-3465 4105);
DISPLAY 0.787234 (-3465 4105);
FORCEPROP 1 LASTPIN (-3475 3925) $PN 2
J 0
(-3465 3905);
DISPLAY 0.787234 (-3465 3905);
FORCEPROP 2 LAST CDS_LIB pure_quanta
J 0
(-3475 4025);
PAINT MONO (-3475 4025);
DISPLAY INVISIBLE (-3475 4025);
FORCEPROP 2 LAST CDS_LOCATION C498
J 0
(-3425 4225);
DISPLAY 1.021277 (-3425 4225);
DISPLAY INVISIBLE (-3425 4225);
FORCEPROP 2 LAST $SEC 1
J 0
(-3425 4225);
DISPLAY 0.680851 (-3425 4225);
PAINT MONO (-3425 4225);
DISPLAY INVISIBLE (-3425 4225);
FORCEPROP 2 LAST CDS_SEC 1
J 0
(-3425 4225);
DISPLAY 1.021277 (-3425 4225);
DISPLAY INVISIBLE (-3425 4225);
FORCEPROP 1 LAST PATH I2
J 0
(-3425 4175);
DISPLAY 0.978723 (-3425 4175);
PAINT WHITE (-3425 4175);
DISPLAY INVISIBLE (-3425 4175);
FORCEADD Q_CAP..1
(-3475 7950);
FORCEPROP 1 LAST PART_NUMBER CH647KMEA04
J 0
(-3425 7800);
DISPLAY 0.638298 (-3425 7800);
DISPLAY INVISIBLE (-3425 7800);
FORCEPROP 1 LAST VALUE 47UF
J 0
(-3425 8000);
DISPLAY 0.638298 (-3425 8000);
FORCEPROP 1 LAST TOLERANCE 20%
J 0
(-3425 7900);
DISPLAY 0.638298 (-3425 7900);
FORCEPROP 1 LAST VOLTAGE 4V
J 0
(-3425 7950);
DISPLAY 0.638298 (-3425 7950);
FORCEPROP 1 LAST PACK_TYPE C0805
J 0
(-3425 7750);
DISPLAY 0.638298 (-3425 7750);
FORCEPROP 1 LAST MATERIAL X6S
J 0
(-3425 7850);
DISPLAY 0.638298 (-3425 7850);
FORCEPROP 1 LAST $LOCATION C503
J 0
(-3425 8050);
DISPLAY 0.978723 (-3425 8050);
FORCEPROP 1 LASTPIN (-3475 8050) $PN 1
J 0
(-3465 8030);
DISPLAY 0.787234 (-3465 8030);
FORCEPROP 1 LASTPIN (-3475 7850) $PN 2
J 0
(-3465 7830);
DISPLAY 0.787234 (-3465 7830);
FORCEPROP 2 LAST CDS_LIB pure_quanta
J 0
(-3475 7950);
PAINT MONO (-3475 7950);
DISPLAY INVISIBLE (-3475 7950);
FORCEPROP 2 LAST CDS_LOCATION C503
J 0
(-3425 8150);
DISPLAY 1.021277 (-3425 8150);
DISPLAY INVISIBLE (-3425 8150);
FORCEPROP 2 LAST $SEC 1
J 0
(-3425 8150);
DISPLAY 0.680851 (-3425 8150);
PAINT MONO (-3425 8150);
DISPLAY INVISIBLE (-3425 8150);
FORCEPROP 2 LAST CDS_SEC 1
J 0
(-3425 8150);
DISPLAY 1.021277 (-3425 8150);
DISPLAY INVISIBLE (-3425 8150);
FORCEPROP 1 LAST PATH I20
J 0
(-3425 8100);
DISPLAY 0.978723 (-3425 8100);
PAINT WHITE (-3425 8100);
DISPLAY INVISIBLE (-3425 8100);
FORCEADD Q_CAP..1
(-3025 7950);
FORCEPROP 1 LAST PART_NUMBER CH647KMEA04
J 0
(-2975 7800);
DISPLAY 0.638298 (-2975 7800);
DISPLAY INVISIBLE (-2975 7800);
FORCEPROP 1 LAST VALUE 47UF
J 0
(-2975 8000);
DISPLAY 0.638298 (-2975 8000);
FORCEPROP 1 LAST TOLERANCE 20%
J 0
(-2975 7900);
DISPLAY 0.638298 (-2975 7900);
FORCEPROP 1 LAST VOLTAGE 4V
J 0
(-2975 7950);
DISPLAY 0.638298 (-2975 7950);
FORCEPROP 1 LAST PACK_TYPE C0805
J 0
(-2975 7750);
DISPLAY 0.638298 (-2975 7750);
FORCEPROP 1 LAST MATERIAL X6S
J 0
(-2975 7850);
DISPLAY 0.638298 (-2975 7850);
FORCEPROP 1 LAST $LOCATION C507
J 0
(-2975 8050);
DISPLAY 0.978723 (-2975 8050);
FORCEPROP 1 LASTPIN (-3025 8050) $PN 1
J 0
(-3015 8030);
DISPLAY 0.787234 (-3015 8030);
FORCEPROP 1 LASTPIN (-3025 7850) $PN 2
J 0
(-3015 7830);
DISPLAY 0.787234 (-3015 7830);
FORCEPROP 2 LAST CDS_LIB pure_quanta
J 0
(-3025 7950);
PAINT MONO (-3025 7950);
DISPLAY INVISIBLE (-3025 7950);
FORCEPROP 2 LAST CDS_LOCATION C507
J 0
(-2975 8150);
DISPLAY 1.021277 (-2975 8150);
DISPLAY INVISIBLE (-2975 8150);
FORCEPROP 2 LAST $SEC 1
J 0
(-2975 8150);
DISPLAY 0.680851 (-2975 8150);
PAINT MONO (-2975 8150);
DISPLAY INVISIBLE (-2975 8150);
FORCEPROP 2 LAST CDS_SEC 1
J 0
(-2975 8150);
DISPLAY 1.021277 (-2975 8150);
DISPLAY INVISIBLE (-2975 8150);
FORCEPROP 1 LAST PATH I21
J 0
(-2975 8100);
DISPLAY 0.978723 (-2975 8100);
PAINT WHITE (-2975 8100);
DISPLAY INVISIBLE (-2975 8100);
FORCEADD Q_CAP..1
(-3925 8825);
FORCEPROP 1 LAST PART_NUMBER CH647KMEA04
J 0
(-3875 8675);
DISPLAY 0.638298 (-3875 8675);
DISPLAY INVISIBLE (-3875 8675);
FORCEPROP 1 LAST TOLERANCE 20%
J 0
(-3875 8775);
DISPLAY 0.638298 (-3875 8775);
FORCEPROP 1 LAST VOLTAGE 4V
J 0
(-3875 8825);
DISPLAY 0.638298 (-3875 8825);
FORCEPROP 1 LAST PACK_TYPE C0805
J 0
(-3875 8625);
DISPLAY 0.638298 (-3875 8625);
FORCEPROP 1 LAST VALUE 47UF
J 0
(-3875 8875);
DISPLAY 0.638298 (-3875 8875);
FORCEPROP 1 LAST MATERIAL X6S
J 0
(-3875 8725);
DISPLAY 0.638298 (-3875 8725);
FORCEPROP 1 LAST $LOCATION C386
J 0
(-3875 8925);
DISPLAY 0.638298 (-3875 8925);
FORCEPROP 1 LASTPIN (-3925 8925) $PN 1
J 0
(-3915 8905);
DISPLAY 0.787234 (-3915 8905);
FORCEPROP 1 LASTPIN (-3925 8725) $PN 2
J 0
(-3915 8705);
DISPLAY 0.787234 (-3915 8705);
FORCEPROP 2 LAST CDS_LIB pure_quanta
J 0
(-3925 8825);
PAINT MONO (-3925 8825);
DISPLAY INVISIBLE (-3925 8825);
FORCEPROP 1 LAST $LOCATION C386
J 0
(-3875 9025);
DISPLAY 1.021277 (-3875 9025);
DISPLAY INVISIBLE (-3875 9025);
FORCEPROP 2 LAST CDS_LOCATION C386
J 0
(-3875 9025);
DISPLAY 1.021277 (-3875 9025);
DISPLAY INVISIBLE (-3875 9025);
FORCEPROP 2 LAST $SEC 1
J 0
(-3875 9025);
DISPLAY 0.680851 (-3875 9025);
PAINT MONO (-3875 9025);
DISPLAY INVISIBLE (-3875 9025);
FORCEPROP 2 LAST CDS_SEC 1
J 0
(-3875 9025);
DISPLAY 1.021277 (-3875 9025);
DISPLAY INVISIBLE (-3875 9025);
FORCEPROP 1 LAST PATH I22
J 0
(-3875 8975);
DISPLAY 0.978723 (-3875 8975);
PAINT WHITE (-3875 8975);
DISPLAY INVISIBLE (-3875 8975);
FORCEADD Q_CAP..1
(-3475 8825);
FORCEPROP 1 LAST PART_NUMBER CH647KMEA04
J 0
(-3425 8675);
DISPLAY 0.638298 (-3425 8675);
DISPLAY INVISIBLE (-3425 8675);
FORCEPROP 1 LAST TOLERANCE 20%
J 0
(-3425 8775);
DISPLAY 0.638298 (-3425 8775);
FORCEPROP 1 LAST VOLTAGE 4V
J 0
(-3425 8825);
DISPLAY 0.638298 (-3425 8825);
FORCEPROP 1 LAST PACK_TYPE C0805
J 0
(-3425 8625);
DISPLAY 0.638298 (-3425 8625);
FORCEPROP 1 LAST VALUE 47UF
J 0
(-3425 8875);
DISPLAY 0.638298 (-3425 8875);
FORCEPROP 1 LAST MATERIAL X6S
J 0
(-3425 8725);
DISPLAY 0.638298 (-3425 8725);
FORCEPROP 1 LAST $LOCATION C388
J 0
(-3425 8925);
DISPLAY 0.638298 (-3425 8925);
FORCEPROP 1 LASTPIN (-3475 8925) $PN 1
J 0
(-3465 8905);
DISPLAY 0.787234 (-3465 8905);
FORCEPROP 1 LASTPIN (-3475 8725) $PN 2
J 0
(-3465 8705);
DISPLAY 0.787234 (-3465 8705);
FORCEPROP 2 LAST CDS_LIB pure_quanta
J 0
(-3475 8825);
PAINT MONO (-3475 8825);
DISPLAY INVISIBLE (-3475 8825);
FORCEPROP 1 LAST $LOCATION C388
J 0
(-3425 9025);
DISPLAY 1.021277 (-3425 9025);
DISPLAY INVISIBLE (-3425 9025);
FORCEPROP 2 LAST CDS_LOCATION C388
J 0
(-3425 9025);
DISPLAY 1.021277 (-3425 9025);
DISPLAY INVISIBLE (-3425 9025);
FORCEPROP 2 LAST $SEC 1
J 0
(-3425 9025);
DISPLAY 0.680851 (-3425 9025);
PAINT MONO (-3425 9025);
DISPLAY INVISIBLE (-3425 9025);
FORCEPROP 2 LAST CDS_SEC 1
J 0
(-3425 9025);
DISPLAY 1.021277 (-3425 9025);
DISPLAY INVISIBLE (-3425 9025);
FORCEPROP 1 LAST PATH I23
J 0
(-3425 8975);
DISPLAY 0.978723 (-3425 8975);
PAINT WHITE (-3425 8975);
DISPLAY INVISIBLE (-3425 8975);
FORCEADD UNIVERSAL_POWER..1
(-3925 9100);
FORCEPROP 3 LASTPIN (-3925 9050) SIG_NAME PVCCIN_CPU0\g
J 0
(-3915 9060);
DISPLAY 0.659574 (-3915 9060);
PAINT MONO (-3915 9060);
DISPLAY INVISIBLE (-3915 9060);
FORCEPROP 1 LAST HDL_POWER PVCCIN_CPU0
J 1
(-3725 9150);
DISPLAY 0.872340 (-3725 9150);
PAINT GREEN (-3725 9150);
FORCEPROP 2 LAST CDS_LIB logical_power
J 0
(-3925 9100);
DISPLAY INVISIBLE (-3925 9100);
FORCEPROP 1 LAST PATH I24
J 0
(-3875 9125);
DISPLAY 0.872340 (-3875 9125);
PAINT AQUA (-3875 9125);
DISPLAY INVISIBLE (-3875 9125);
FORCEADD Q_CAP..1
(-3025 8825);
FORCEPROP 1 LAST PART_NUMBER CH647KMEA04
J 0
(-2975 8675);
DISPLAY 0.638298 (-2975 8675);
DISPLAY INVISIBLE (-2975 8675);
FORCEPROP 1 LAST TOLERANCE 20%
J 0
(-2975 8775);
DISPLAY 0.638298 (-2975 8775);
FORCEPROP 1 LAST VOLTAGE 4V
J 0
(-2975 8825);
DISPLAY 0.638298 (-2975 8825);
FORCEPROP 1 LAST PACK_TYPE C0805
J 0
(-2975 8625);
DISPLAY 0.638298 (-2975 8625);
FORCEPROP 1 LAST VALUE 47UF
J 0
(-2975 8875);
DISPLAY 0.638298 (-2975 8875);
FORCEPROP 1 LAST MATERIAL X6S
J 0
(-2975 8725);
DISPLAY 0.638298 (-2975 8725);
FORCEPROP 1 LAST $LOCATION C390
J 0
(-2975 8925);
DISPLAY 0.638298 (-2975 8925);
FORCEPROP 1 LASTPIN (-3025 8925) $PN 1
J 0
(-3015 8905);
DISPLAY 0.787234 (-3015 8905);
FORCEPROP 1 LASTPIN (-3025 8725) $PN 2
J 0
(-3015 8705);
DISPLAY 0.787234 (-3015 8705);
FORCEPROP 2 LAST CDS_LIB pure_quanta
J 0
(-3025 8825);
PAINT MONO (-3025 8825);
DISPLAY INVISIBLE (-3025 8825);
FORCEPROP 1 LAST $LOCATION C390
J 0
(-2975 9025);
DISPLAY 1.021277 (-2975 9025);
DISPLAY INVISIBLE (-2975 9025);
FORCEPROP 2 LAST CDS_LOCATION C390
J 0
(-2975 9025);
DISPLAY 1.021277 (-2975 9025);
DISPLAY INVISIBLE (-2975 9025);
FORCEPROP 2 LAST $SEC 1
J 0
(-2975 9025);
DISPLAY 0.680851 (-2975 9025);
PAINT MONO (-2975 9025);
DISPLAY INVISIBLE (-2975 9025);
FORCEPROP 2 LAST CDS_SEC 1
J 0
(-2975 9025);
DISPLAY 1.021277 (-2975 9025);
DISPLAY INVISIBLE (-2975 9025);
FORCEPROP 1 LAST PATH I25
J 0
(-2975 8975);
DISPLAY 0.978723 (-2975 8975);
PAINT WHITE (-2975 8975);
DISPLAY INVISIBLE (-2975 8975);
FORCEADD Q_CAP..1
(-2575 4025);
FORCEPROP 1 LAST PART_NUMBER CH647KMEA04
J 0
(-2525 3875);
DISPLAY 0.638298 (-2525 3875);
DISPLAY INVISIBLE (-2525 3875);
FORCEPROP 1 LAST TOLERANCE 20%
J 0
(-2525 3975);
DISPLAY 0.638298 (-2525 3975);
FORCEPROP 1 LAST VOLTAGE 4V
J 0
(-2525 4025);
DISPLAY 0.638298 (-2525 4025);
FORCEPROP 1 LAST PACK_TYPE C0805
J 0
(-2525 3825);
DISPLAY 0.638298 (-2525 3825);
FORCEPROP 1 LAST VALUE 47UF
J 0
(-2525 4075);
DISPLAY 0.638298 (-2525 4075);
FORCEPROP 1 LAST MATERIAL X6S
J 0
(-2525 3925);
DISPLAY 0.638298 (-2525 3925);
FORCEPROP 1 LAST $LOCATION C506
J 0
(-2525 4125);
DISPLAY 0.978723 (-2525 4125);
FORCEPROP 1 LASTPIN (-2575 4125) $PN 1
J 0
(-2565 4105);
DISPLAY 0.787234 (-2565 4105);
FORCEPROP 1 LASTPIN (-2575 3925) $PN 2
J 0
(-2565 3905);
DISPLAY 0.787234 (-2565 3905);
FORCEPROP 2 LAST CDS_LIB pure_quanta
J 0
(-2575 4025);
PAINT MONO (-2575 4025);
DISPLAY INVISIBLE (-2575 4025);
FORCEPROP 2 LAST CDS_LOCATION C506
J 0
(-2525 4225);
DISPLAY 1.021277 (-2525 4225);
DISPLAY INVISIBLE (-2525 4225);
FORCEPROP 2 LAST $SEC 1
J 0
(-2525 4225);
DISPLAY 0.680851 (-2525 4225);
PAINT MONO (-2525 4225);
DISPLAY INVISIBLE (-2525 4225);
FORCEPROP 2 LAST CDS_SEC 1
J 0
(-2525 4225);
DISPLAY 1.021277 (-2525 4225);
DISPLAY INVISIBLE (-2525 4225);
FORCEPROP 1 LAST PATH I26
J 0
(-2525 4175);
DISPLAY 0.978723 (-2525 4175);
PAINT WHITE (-2525 4175);
DISPLAY INVISIBLE (-2525 4175);
FORCEADD Q_CAP..1
(-2125 4025);
FORCEPROP 1 LAST PART_NUMBER CH647KMEA04
J 0
(-2075 3875);
DISPLAY 0.638298 (-2075 3875);
DISPLAY INVISIBLE (-2075 3875);
FORCEPROP 1 LAST TOLERANCE 20%
J 0
(-2075 3975);
DISPLAY 0.638298 (-2075 3975);
FORCEPROP 1 LAST VOLTAGE 4V
J 0
(-2075 4025);
DISPLAY 0.638298 (-2075 4025);
FORCEPROP 1 LAST PACK_TYPE C0805
J 0
(-2075 3825);
DISPLAY 0.638298 (-2075 3825);
FORCEPROP 1 LAST VALUE 47UF
J 0
(-2075 4075);
DISPLAY 0.638298 (-2075 4075);
FORCEPROP 1 LAST MATERIAL X6S
J 0
(-2075 3925);
DISPLAY 0.638298 (-2075 3925);
FORCEPROP 1 LAST $LOCATION C510
J 0
(-2075 4125);
DISPLAY 0.978723 (-2075 4125);
FORCEPROP 1 LASTPIN (-2125 4125) $PN 1
J 0
(-2115 4105);
DISPLAY 0.787234 (-2115 4105);
FORCEPROP 1 LASTPIN (-2125 3925) $PN 2
J 0
(-2115 3905);
DISPLAY 0.787234 (-2115 3905);
FORCEPROP 2 LAST CDS_LIB pure_quanta
J 0
(-2125 4025);
PAINT MONO (-2125 4025);
DISPLAY INVISIBLE (-2125 4025);
FORCEPROP 2 LAST CDS_LOCATION C510
J 0
(-2075 4225);
DISPLAY 1.021277 (-2075 4225);
DISPLAY INVISIBLE (-2075 4225);
FORCEPROP 2 LAST $SEC 1
J 0
(-2075 4225);
DISPLAY 0.680851 (-2075 4225);
PAINT MONO (-2075 4225);
DISPLAY INVISIBLE (-2075 4225);
FORCEPROP 2 LAST CDS_SEC 1
J 0
(-2075 4225);
DISPLAY 1.021277 (-2075 4225);
DISPLAY INVISIBLE (-2075 4225);
FORCEPROP 1 LAST PATH I27
J 0
(-2075 4175);
DISPLAY 0.978723 (-2075 4175);
PAINT WHITE (-2075 4175);
DISPLAY INVISIBLE (-2075 4175);
FORCEADD Q_CAP..1
(-1675 4025);
FORCEPROP 1 LAST PART_NUMBER CH647KMEA04
J 0
(-1625 3875);
DISPLAY 0.638298 (-1625 3875);
DISPLAY INVISIBLE (-1625 3875);
FORCEPROP 1 LAST TOLERANCE 20%
J 0
(-1625 3975);
DISPLAY 0.638298 (-1625 3975);
FORCEPROP 1 LAST VOLTAGE 4V
J 0
(-1625 4025);
DISPLAY 0.638298 (-1625 4025);
FORCEPROP 1 LAST PACK_TYPE C0805
J 0
(-1625 3825);
DISPLAY 0.638298 (-1625 3825);
FORCEPROP 1 LAST VALUE 47UF
J 0
(-1625 4075);
DISPLAY 0.638298 (-1625 4075);
FORCEPROP 1 LAST MATERIAL X6S
J 0
(-1625 3925);
DISPLAY 0.638298 (-1625 3925);
FORCEPROP 1 LAST $LOCATION C514
J 0
(-1625 4125);
DISPLAY 0.978723 (-1625 4125);
FORCEPROP 1 LASTPIN (-1675 4125) $PN 1
J 0
(-1665 4105);
DISPLAY 0.787234 (-1665 4105);
FORCEPROP 1 LASTPIN (-1675 3925) $PN 2
J 0
(-1665 3905);
DISPLAY 0.787234 (-1665 3905);
FORCEPROP 2 LAST CDS_LIB pure_quanta
J 0
(-1675 4025);
PAINT MONO (-1675 4025);
DISPLAY INVISIBLE (-1675 4025);
FORCEPROP 2 LAST CDS_LOCATION C514
J 0
(-1625 4225);
DISPLAY 1.021277 (-1625 4225);
DISPLAY INVISIBLE (-1625 4225);
FORCEPROP 2 LAST $SEC 1
J 0
(-1625 4225);
DISPLAY 0.680851 (-1625 4225);
PAINT MONO (-1625 4225);
DISPLAY INVISIBLE (-1625 4225);
FORCEPROP 2 LAST CDS_SEC 1
J 0
(-1625 4225);
DISPLAY 1.021277 (-1625 4225);
DISPLAY INVISIBLE (-1625 4225);
FORCEPROP 1 LAST PATH I28
J 0
(-1625 4175);
DISPLAY 0.978723 (-1625 4175);
PAINT WHITE (-1625 4175);
DISPLAY INVISIBLE (-1625 4175);
FORCEADD Q_CAP..1
(-1225 4025);
FORCEPROP 1 LAST PART_NUMBER CH647KMEA04
J 0
(-1175 3875);
DISPLAY 0.638298 (-1175 3875);
DISPLAY INVISIBLE (-1175 3875);
FORCEPROP 1 LAST TOLERANCE 20%
J 0
(-1175 3975);
DISPLAY 0.638298 (-1175 3975);
FORCEPROP 1 LAST VOLTAGE 4V
J 0
(-1175 4025);
DISPLAY 0.638298 (-1175 4025);
FORCEPROP 1 LAST PACK_TYPE C0805
J 0
(-1175 3825);
DISPLAY 0.638298 (-1175 3825);
FORCEPROP 1 LAST VALUE 47UF
J 0
(-1175 4075);
DISPLAY 0.638298 (-1175 4075);
FORCEPROP 1 LAST MATERIAL X6S
J 0
(-1175 3925);
DISPLAY 0.638298 (-1175 3925);
FORCEPROP 1 LAST $LOCATION C517
J 0
(-1175 4125);
DISPLAY 0.978723 (-1175 4125);
FORCEPROP 1 LASTPIN (-1225 4125) $PN 1
J 0
(-1215 4105);
DISPLAY 0.787234 (-1215 4105);
FORCEPROP 1 LASTPIN (-1225 3925) $PN 2
J 0
(-1215 3905);
DISPLAY 0.787234 (-1215 3905);
FORCEPROP 2 LAST CDS_LIB pure_quanta
J 0
(-1225 4025);
PAINT MONO (-1225 4025);
DISPLAY INVISIBLE (-1225 4025);
FORCEPROP 2 LAST CDS_LOCATION C517
J 0
(-1175 4225);
DISPLAY 1.021277 (-1175 4225);
DISPLAY INVISIBLE (-1175 4225);
FORCEPROP 2 LAST $SEC 1
J 0
(-1175 4225);
DISPLAY 0.680851 (-1175 4225);
PAINT MONO (-1175 4225);
DISPLAY INVISIBLE (-1175 4225);
FORCEPROP 2 LAST CDS_SEC 1
J 0
(-1175 4225);
DISPLAY 1.021277 (-1175 4225);
DISPLAY INVISIBLE (-1175 4225);
FORCEPROP 1 LAST PATH I29
J 0
(-1175 4175);
DISPLAY 0.978723 (-1175 4175);
PAINT WHITE (-1175 4175);
DISPLAY INVISIBLE (-1175 4175);
FORCEADD Q_CAP..1
(-3025 4025);
FORCEPROP 1 LAST PART_NUMBER CH647KMEA04
J 0
(-2975 3875);
DISPLAY 0.638298 (-2975 3875);
DISPLAY INVISIBLE (-2975 3875);
FORCEPROP 1 LAST TOLERANCE 20%
J 0
(-2975 3975);
DISPLAY 0.638298 (-2975 3975);
FORCEPROP 1 LAST VOLTAGE 4V
J 0
(-2975 4025);
DISPLAY 0.638298 (-2975 4025);
FORCEPROP 1 LAST PACK_TYPE C0805
J 0
(-2975 3825);
DISPLAY 0.638298 (-2975 3825);
FORCEPROP 1 LAST VALUE 47UF
J 0
(-2975 4075);
DISPLAY 0.638298 (-2975 4075);
FORCEPROP 1 LAST MATERIAL X6S
J 0
(-2975 3925);
DISPLAY 0.638298 (-2975 3925);
FORCEPROP 1 LAST $LOCATION C502
J 0
(-2975 4125);
DISPLAY 0.978723 (-2975 4125);
FORCEPROP 1 LASTPIN (-3025 4125) $PN 1
J 0
(-3015 4105);
DISPLAY 0.787234 (-3015 4105);
FORCEPROP 1 LASTPIN (-3025 3925) $PN 2
J 0
(-3015 3905);
DISPLAY 0.787234 (-3015 3905);
FORCEPROP 2 LAST CDS_LIB pure_quanta
J 0
(-3025 4025);
PAINT MONO (-3025 4025);
DISPLAY INVISIBLE (-3025 4025);
FORCEPROP 2 LAST CDS_LOCATION C502
J 0
(-2975 4225);
DISPLAY 1.021277 (-2975 4225);
DISPLAY INVISIBLE (-2975 4225);
FORCEPROP 2 LAST $SEC 1
J 0
(-2975 4225);
DISPLAY 0.680851 (-2975 4225);
PAINT MONO (-2975 4225);
DISPLAY INVISIBLE (-2975 4225);
FORCEPROP 2 LAST CDS_SEC 1
J 0
(-2975 4225);
DISPLAY 1.021277 (-2975 4225);
DISPLAY INVISIBLE (-2975 4225);
FORCEPROP 1 LAST PATH I3
J 0
(-2975 4175);
DISPLAY 0.978723 (-2975 4175);
PAINT WHITE (-2975 4175);
DISPLAY INVISIBLE (-2975 4175);
FORCEADD UNIVERSAL_GND..1
(-2575 4725);
FORCEPROP 3 LASTPIN (-2575 4775) SIG_NAME GND\g
J 0
(-2565 4785);
DISPLAY 0.659574 (-2565 4785);
PAINT MONO (-2565 4785);
DISPLAY INVISIBLE (-2565 4785);
FORCEPROP 2 LAST CDS_LIB logical_power
J 0
(-2575 4725);
PAINT MONO (-2575 4725);
DISPLAY INVISIBLE (-2575 4725);
FORCEPROP 1 LAST HDL_POWER GND
J 1
(-2550 4650);
DISPLAY 0.872340 (-2550 4650);
PAINT GREEN (-2550 4650);
DISPLAY INVISIBLE (-2550 4650);
FORCEPROP 1 LAST PATH I30
J 0
(-2500 4725);
DISPLAY 0.872340 (-2500 4725);
PAINT AQUA (-2500 4725);
DISPLAY INVISIBLE (-2500 4725);
FORCEADD Q_CAP..1
(-2575 5075);
FORCEPROP 1 LAST PART_NUMBER CH647KMEA04
J 0
(-2525 4925);
DISPLAY 0.638298 (-2525 4925);
DISPLAY INVISIBLE (-2525 4925);
FORCEPROP 1 LAST MATERIAL X6S
J 0
(-2525 4975);
DISPLAY 0.638298 (-2525 4975);
FORCEPROP 1 LAST TOLERANCE 20%
J 0
(-2525 5025);
DISPLAY 0.638298 (-2525 5025);
FORCEPROP 1 LAST VOLTAGE 4V
J 0
(-2525 5075);
DISPLAY 0.638298 (-2525 5075);
FORCEPROP 1 LAST PACK_TYPE C0805
J 0
(-2525 4875);
DISPLAY 0.638298 (-2525 4875);
FORCEPROP 1 LAST VALUE 47UF
J 0
(-2525 5125);
DISPLAY 0.638298 (-2525 5125);
FORCEPROP 1 LAST $LOCATION C531
J 0
(-2525 5175);
DISPLAY 0.978723 (-2525 5175);
FORCEPROP 1 LASTPIN (-2575 5175) $PN 1
J 0
(-2565 5155);
DISPLAY 0.787234 (-2565 5155);
FORCEPROP 1 LASTPIN (-2575 4975) $PN 2
J 0
(-2565 4955);
DISPLAY 0.787234 (-2565 4955);
FORCEPROP 2 LAST CDS_LIB pure_quanta
J 0
(-2575 5075);
PAINT MONO (-2575 5075);
DISPLAY INVISIBLE (-2575 5075);
FORCEPROP 2 LAST CDS_LOCATION C531
J 0
(-2525 5275);
DISPLAY 1.021277 (-2525 5275);
DISPLAY INVISIBLE (-2525 5275);
FORCEPROP 2 LAST $SEC 1
J 0
(-2525 5275);
DISPLAY 0.680851 (-2525 5275);
PAINT MONO (-2525 5275);
DISPLAY INVISIBLE (-2525 5275);
FORCEPROP 2 LAST CDS_SEC 1
J 0
(-2525 5275);
DISPLAY 1.021277 (-2525 5275);
DISPLAY INVISIBLE (-2525 5275);
FORCEPROP 1 LAST PATH I31
J 0
(-2525 5225);
DISPLAY 0.978723 (-2525 5225);
PAINT WHITE (-2525 5225);
DISPLAY INVISIBLE (-2525 5225);
FORCEADD Q_CAP..1
(-2575 6100);
FORCEPROP 1 LAST PART_NUMBER CH647KMEA04
J 0
(-2525 5950);
DISPLAY 0.638298 (-2525 5950);
DISPLAY INVISIBLE (-2525 5950);
FORCEPROP 1 LAST VALUE 47UF
J 0
(-2525 6150);
DISPLAY 0.638298 (-2525 6150);
FORCEPROP 1 LAST TOLERANCE 20%
J 0
(-2525 6050);
DISPLAY 0.638298 (-2525 6050);
FORCEPROP 1 LAST VOLTAGE 4V
J 0
(-2525 6100);
DISPLAY 0.638298 (-2525 6100);
FORCEPROP 1 LAST PACK_TYPE C0805
J 0
(-2525 5900);
DISPLAY 0.638298 (-2525 5900);
FORCEPROP 1 LAST MATERIAL X6S
J 0
(-2525 6000);
DISPLAY 0.638298 (-2525 6000);
FORCEPROP 1 LAST $LOCATION C512
J 0
(-2525 6200);
DISPLAY 0.978723 (-2525 6200);
FORCEPROP 1 LASTPIN (-2575 6200) $PN 1
J 0
(-2565 6180);
DISPLAY 0.787234 (-2565 6180);
FORCEPROP 1 LASTPIN (-2575 6000) $PN 2
J 0
(-2565 5980);
DISPLAY 0.787234 (-2565 5980);
FORCEPROP 2 LAST CDS_LIB pure_quanta
J 0
(-2575 6100);
PAINT MONO (-2575 6100);
DISPLAY INVISIBLE (-2575 6100);
FORCEPROP 2 LAST CDS_LOCATION C512
J 0
(-2525 6300);
DISPLAY 1.021277 (-2525 6300);
DISPLAY INVISIBLE (-2525 6300);
FORCEPROP 2 LAST $SEC 1
J 0
(-2525 6300);
DISPLAY 0.680851 (-2525 6300);
PAINT MONO (-2525 6300);
DISPLAY INVISIBLE (-2525 6300);
FORCEPROP 2 LAST CDS_SEC 1
J 0
(-2525 6300);
DISPLAY 1.021277 (-2525 6300);
DISPLAY INVISIBLE (-2525 6300);
FORCEPROP 1 LAST PATH I32
J 0
(-2525 6250);
DISPLAY 0.978723 (-2525 6250);
PAINT WHITE (-2525 6250);
DISPLAY INVISIBLE (-2525 6250);
FORCEADD Q_CAP..1
(-2125 6100);
FORCEPROP 1 LAST PART_NUMBER CH647LME900
J 0
(-2075 5950);
DISPLAY 0.638298 (-2075 5950);
DISPLAY INVISIBLE (-2075 5950);
FORCEPROP 1 LAST TOLERANCE 20%
J 0
(-2075 6050);
DISPLAY 0.638298 (-2075 6050);
FORCEPROP 1 LAST MATERIAL X6S
J 0
(-2075 6000);
DISPLAY 0.638298 (-2075 6000);
FORCEPROP 1 LAST PACK_TYPE C0603
J 0
(-2075 5900);
DISPLAY 0.638298 (-2075 5900);
FORCEPROP 1 LAST VOLTAGE 2.5V
J 0
(-2075 6100);
DISPLAY 0.638298 (-2075 6100);
FORCEPROP 1 LAST VALUE 47UF
J 0
(-2075 6150);
DISPLAY 0.638298 (-2075 6150);
FORCEPROP 1 LAST $LOCATION C516
J 0
(-2075 6200);
DISPLAY 0.978723 (-2075 6200);
FORCEPROP 1 LASTPIN (-2125 6200) $PN 1
J 0
(-2115 6180);
DISPLAY 0.787234 (-2115 6180);
FORCEPROP 1 LASTPIN (-2125 6000) $PN 2
J 0
(-2115 5980);
DISPLAY 0.787234 (-2115 5980);
FORCEPROP 2 LAST CDS_LIB pure_quanta
J 0
(-2125 6100);
PAINT MONO (-2125 6100);
DISPLAY INVISIBLE (-2125 6100);
FORCEPROP 2 LAST CDS_LOCATION C516
J 0
(-2075 6300);
DISPLAY 1.021277 (-2075 6300);
DISPLAY INVISIBLE (-2075 6300);
FORCEPROP 2 LAST $SEC 1
J 0
(-2075 6300);
DISPLAY 0.680851 (-2075 6300);
PAINT MONO (-2075 6300);
DISPLAY INVISIBLE (-2075 6300);
FORCEPROP 2 LAST CDS_SEC 1
J 0
(-2075 6300);
DISPLAY 1.021277 (-2075 6300);
DISPLAY INVISIBLE (-2075 6300);
FORCEPROP 1 LAST PATH I33
J 0
(-2075 6250);
DISPLAY 0.978723 (-2075 6250);
PAINT WHITE (-2075 6250);
DISPLAY INVISIBLE (-2075 6250);
FORCEADD UNIVERSAL_GND..1
(-1675 5750);
FORCEPROP 3 LASTPIN (-1675 5800) SIG_NAME GND\g
J 0
(-1665 5810);
DISPLAY 0.659574 (-1665 5810);
PAINT MONO (-1665 5810);
DISPLAY INVISIBLE (-1665 5810);
FORCEPROP 2 LAST CDS_LIB logical_power
J 0
(-1675 5750);
PAINT MONO (-1675 5750);
DISPLAY INVISIBLE (-1675 5750);
FORCEPROP 1 LAST HDL_POWER GND
J 1
(-1650 5675);
DISPLAY 0.872340 (-1650 5675);
PAINT GREEN (-1650 5675);
DISPLAY INVISIBLE (-1650 5675);
FORCEPROP 1 LAST PATH I34
J 0
(-1600 5750);
DISPLAY 0.872340 (-1600 5750);
PAINT AQUA (-1600 5750);
DISPLAY INVISIBLE (-1600 5750);
FORCEADD Q_CAP..1
(-1675 6100);
FORCEPROP 1 LAST PART_NUMBER CH647LME900
J 0
(-1625 5950);
DISPLAY 0.638298 (-1625 5950);
DISPLAY INVISIBLE (-1625 5950);
FORCEPROP 1 LAST TOLERANCE 20%
J 0
(-1625 6050);
DISPLAY 0.638298 (-1625 6050);
FORCEPROP 1 LAST VOLTAGE 2.5V
J 0
(-1625 6100);
DISPLAY 0.638298 (-1625 6100);
FORCEPROP 1 LAST MATERIAL X6S
J 0
(-1625 6000);
DISPLAY 0.638298 (-1625 6000);
FORCEPROP 1 LAST PACK_TYPE C0603
J 0
(-1625 5900);
DISPLAY 0.638298 (-1625 5900);
FORCEPROP 1 LAST VALUE 47UF
J 0
(-1625 6150);
DISPLAY 0.638298 (-1625 6150);
FORCEPROP 1 LAST $LOCATION C519
J 0
(-1625 6200);
DISPLAY 0.978723 (-1625 6200);
FORCEPROP 1 LASTPIN (-1675 6200) $PN 1
J 0
(-1665 6180);
DISPLAY 0.787234 (-1665 6180);
FORCEPROP 1 LASTPIN (-1675 6000) $PN 2
J 0
(-1665 5980);
DISPLAY 0.787234 (-1665 5980);
FORCEPROP 2 LAST CDS_LIB pure_quanta
J 0
(-1675 6100);
PAINT MONO (-1675 6100);
DISPLAY INVISIBLE (-1675 6100);
FORCEPROP 2 LAST CDS_LOCATION C519
J 0
(-1625 6300);
DISPLAY 1.021277 (-1625 6300);
DISPLAY INVISIBLE (-1625 6300);
FORCEPROP 2 LAST $SEC 1
J 0
(-1625 6300);
DISPLAY 0.680851 (-1625 6300);
PAINT MONO (-1625 6300);
DISPLAY INVISIBLE (-1625 6300);
FORCEPROP 2 LAST CDS_SEC 1
J 0
(-1625 6300);
DISPLAY 1.021277 (-1625 6300);
DISPLAY INVISIBLE (-1625 6300);
FORCEPROP 1 LAST PATH I35
J 0
(-1625 6250);
DISPLAY 0.978723 (-1625 6250);
PAINT WHITE (-1625 6250);
DISPLAY INVISIBLE (-1625 6250);
FORCEADD Q_CAP..1
(-775 4025);
FORCEPROP 1 LAST PART_NUMBER CH647KMEA04
J 0
(-725 3875);
DISPLAY 0.638298 (-725 3875);
DISPLAY INVISIBLE (-725 3875);
FORCEPROP 1 LAST TOLERANCE 20%
J 0
(-725 3975);
DISPLAY 0.638298 (-725 3975);
FORCEPROP 1 LAST VOLTAGE 4V
J 0
(-725 4025);
DISPLAY 0.638298 (-725 4025);
FORCEPROP 1 LAST PACK_TYPE C0805
J 0
(-725 3825);
DISPLAY 0.638298 (-725 3825);
FORCEPROP 1 LAST VALUE 47UF
J 0
(-725 4075);
DISPLAY 0.638298 (-725 4075);
FORCEPROP 1 LAST MATERIAL X6S
J 0
(-725 3925);
DISPLAY 0.638298 (-725 3925);
FORCEPROP 1 LAST $LOCATION C520
J 0
(-725 4125);
DISPLAY 0.978723 (-725 4125);
FORCEPROP 1 LASTPIN (-775 4125) $PN 1
J 0
(-765 4105);
DISPLAY 0.787234 (-765 4105);
FORCEPROP 1 LASTPIN (-775 3925) $PN 2
J 0
(-765 3905);
DISPLAY 0.787234 (-765 3905);
FORCEPROP 2 LAST CDS_LIB pure_quanta
J 0
(-775 4025);
PAINT MONO (-775 4025);
DISPLAY INVISIBLE (-775 4025);
FORCEPROP 2 LAST CDS_LOCATION C520
J 0
(-725 4225);
DISPLAY 1.021277 (-725 4225);
DISPLAY INVISIBLE (-725 4225);
FORCEPROP 2 LAST $SEC 1
J 0
(-725 4225);
DISPLAY 0.680851 (-725 4225);
PAINT MONO (-725 4225);
DISPLAY INVISIBLE (-725 4225);
FORCEPROP 2 LAST CDS_SEC 1
J 0
(-725 4225);
DISPLAY 1.021277 (-725 4225);
DISPLAY INVISIBLE (-725 4225);
FORCEPROP 1 LAST PATH I36
J 0
(-725 4175);
DISPLAY 0.978723 (-725 4175);
PAINT WHITE (-725 4175);
DISPLAY INVISIBLE (-725 4175);
FORCEADD Q_CAP..1
(-325 4025);
FORCEPROP 1 LAST PART_NUMBER CH647KMEA04
J 0
(-275 3875);
DISPLAY 0.638298 (-275 3875);
DISPLAY INVISIBLE (-275 3875);
FORCEPROP 1 LAST TOLERANCE 20%
J 0
(-275 3975);
DISPLAY 0.638298 (-275 3975);
FORCEPROP 1 LAST VOLTAGE 4V
J 0
(-275 4025);
DISPLAY 0.638298 (-275 4025);
FORCEPROP 1 LAST PACK_TYPE C0805
J 0
(-275 3825);
DISPLAY 0.638298 (-275 3825);
FORCEPROP 1 LAST VALUE 47UF
J 0
(-275 4075);
DISPLAY 0.638298 (-275 4075);
FORCEPROP 1 LAST MATERIAL X6S
J 0
(-275 3925);
DISPLAY 0.638298 (-275 3925);
FORCEPROP 1 LAST $LOCATION C521
J 0
(-275 4125);
DISPLAY 0.978723 (-275 4125);
FORCEPROP 1 LASTPIN (-325 4125) $PN 1
J 0
(-315 4105);
DISPLAY 0.787234 (-315 4105);
FORCEPROP 1 LASTPIN (-325 3925) $PN 2
J 0
(-315 3905);
DISPLAY 0.787234 (-315 3905);
FORCEPROP 2 LAST CDS_LIB pure_quanta
J 0
(-325 4025);
PAINT MONO (-325 4025);
DISPLAY INVISIBLE (-325 4025);
FORCEPROP 2 LAST CDS_LOCATION C521
J 0
(-275 4225);
DISPLAY 1.021277 (-275 4225);
DISPLAY INVISIBLE (-275 4225);
FORCEPROP 2 LAST $SEC 1
J 0
(-275 4225);
DISPLAY 0.680851 (-275 4225);
PAINT MONO (-275 4225);
DISPLAY INVISIBLE (-275 4225);
FORCEPROP 2 LAST CDS_SEC 1
J 0
(-275 4225);
DISPLAY 1.021277 (-275 4225);
DISPLAY INVISIBLE (-275 4225);
FORCEPROP 1 LAST PATH I37
J 0
(-275 4175);
DISPLAY 0.978723 (-275 4175);
PAINT WHITE (-275 4175);
DISPLAY INVISIBLE (-275 4175);
FORCEADD Q_CAP..1
(125 4025);
FORCEPROP 1 LAST PART_NUMBER CH647KMEA04
J 0
(175 3875);
DISPLAY 0.638298 (175 3875);
DISPLAY INVISIBLE (175 3875);
FORCEPROP 1 LAST TOLERANCE 20%
J 0
(175 3975);
DISPLAY 0.638298 (175 3975);
FORCEPROP 1 LAST VOLTAGE 4V
J 0
(175 4025);
DISPLAY 0.638298 (175 4025);
FORCEPROP 1 LAST PACK_TYPE C0805
J 0
(175 3825);
DISPLAY 0.638298 (175 3825);
FORCEPROP 1 LAST VALUE 47UF
J 0
(175 4075);
DISPLAY 0.638298 (175 4075);
FORCEPROP 1 LAST MATERIAL X6S
J 0
(175 3925);
DISPLAY 0.638298 (175 3925);
FORCEPROP 1 LAST $LOCATION C523
J 0
(175 4125);
DISPLAY 0.978723 (175 4125);
FORCEPROP 1 LASTPIN (125 4125) $PN 1
J 0
(135 4105);
DISPLAY 0.787234 (135 4105);
FORCEPROP 1 LASTPIN (125 3925) $PN 2
J 0
(135 3905);
DISPLAY 0.787234 (135 3905);
FORCEPROP 2 LAST CDS_LIB pure_quanta
J 0
(125 4025);
PAINT MONO (125 4025);
DISPLAY INVISIBLE (125 4025);
FORCEPROP 2 LAST CDS_LOCATION C523
J 0
(175 4225);
DISPLAY 1.021277 (175 4225);
DISPLAY INVISIBLE (175 4225);
FORCEPROP 2 LAST $SEC 1
J 0
(175 4225);
DISPLAY 0.680851 (175 4225);
PAINT MONO (175 4225);
DISPLAY INVISIBLE (175 4225);
FORCEPROP 2 LAST CDS_SEC 1
J 0
(175 4225);
DISPLAY 1.021277 (175 4225);
DISPLAY INVISIBLE (175 4225);
FORCEPROP 1 LAST PATH I38
J 0
(175 4175);
DISPLAY 0.978723 (175 4175);
PAINT WHITE (175 4175);
DISPLAY INVISIBLE (175 4175);
FORCEADD Q_CAP..1
(575 4025);
FORCEPROP 1 LAST PART_NUMBER CH647KMEA04
J 0
(625 3875);
DISPLAY 0.638298 (625 3875);
DISPLAY INVISIBLE (625 3875);
FORCEPROP 1 LAST TOLERANCE 20%
J 0
(625 3975);
DISPLAY 0.638298 (625 3975);
FORCEPROP 1 LAST VOLTAGE 4V
J 0
(625 4025);
DISPLAY 0.638298 (625 4025);
FORCEPROP 1 LAST PACK_TYPE C0805
J 0
(625 3825);
DISPLAY 0.638298 (625 3825);
FORCEPROP 1 LAST VALUE 47UF
J 0
(625 4075);
DISPLAY 0.638298 (625 4075);
FORCEPROP 1 LAST MATERIAL X6S
J 0
(625 3925);
DISPLAY 0.638298 (625 3925);
FORCEPROP 1 LAST $LOCATION C526
J 0
(625 4125);
DISPLAY 0.978723 (625 4125);
FORCEPROP 1 LASTPIN (575 4125) $PN 1
J 0
(585 4105);
DISPLAY 0.787234 (585 4105);
FORCEPROP 1 LASTPIN (575 3925) $PN 2
J 0
(585 3905);
DISPLAY 0.787234 (585 3905);
FORCEPROP 2 LAST CDS_LIB pure_quanta
J 0
(575 4025);
PAINT MONO (575 4025);
DISPLAY INVISIBLE (575 4025);
FORCEPROP 2 LAST CDS_LOCATION C526
J 0
(625 4225);
DISPLAY 1.021277 (625 4225);
DISPLAY INVISIBLE (625 4225);
FORCEPROP 2 LAST $SEC 1
J 0
(625 4225);
DISPLAY 0.680851 (625 4225);
PAINT MONO (625 4225);
DISPLAY INVISIBLE (625 4225);
FORCEPROP 2 LAST CDS_SEC 1
J 0
(625 4225);
DISPLAY 1.021277 (625 4225);
DISPLAY INVISIBLE (625 4225);
FORCEPROP 1 LAST PATH I39
J 0
(625 4175);
DISPLAY 0.978723 (625 4175);
PAINT WHITE (625 4175);
DISPLAY INVISIBLE (625 4175);
FORCEADD UNIVERSAL_POWER..1
(-3925 4300);
FORCEPROP 3 LASTPIN (-3925 4250) SIG_NAME PVCCFA_EHV_FIVRA_CPU0\g
J 0
(-3915 4260);
DISPLAY 0.659574 (-3915 4260);
PAINT MONO (-3915 4260);
DISPLAY INVISIBLE (-3915 4260);
FORCEPROP 1 LAST HDL_POWER PVCCFA_EHV_FIVRA_CPU0
J 1
(-3525 4350);
DISPLAY 0.872340 (-3525 4350);
PAINT GREEN (-3525 4350);
FORCEPROP 2 LAST CDS_LIB logical_power
J 0
(-3925 4300);
DISPLAY INVISIBLE (-3925 4300);
FORCEPROP 1 LAST PATH I4
J 0
(-3875 4325);
DISPLAY 0.872340 (-3875 4325);
PAINT AQUA (-3875 4325);
DISPLAY INVISIBLE (-3875 4325);
FORCEADD UNIVERSAL_GND..1
(1025 3675);
FORCEPROP 3 LASTPIN (1025 3725) SIG_NAME GND\g
J 0
(1035 3735);
DISPLAY 0.659574 (1035 3735);
PAINT MONO (1035 3735);
DISPLAY INVISIBLE (1035 3735);
FORCEPROP 2 LAST CDS_LIB logical_power
J 0
(1025 3675);
PAINT MONO (1025 3675);
DISPLAY INVISIBLE (1025 3675);
FORCEPROP 1 LAST HDL_POWER GND
J 1
(1050 3600);
DISPLAY 0.872340 (1050 3600);
PAINT GREEN (1050 3600);
DISPLAY INVISIBLE (1050 3600);
FORCEPROP 1 LAST PATH I40
J 0
(1100 3675);
DISPLAY 0.872340 (1100 3675);
PAINT AQUA (1100 3675);
DISPLAY INVISIBLE (1100 3675);
FORCEADD Q_CAP..1
(1025 4025);
FORCEPROP 1 LAST PART_NUMBER CH647KMEA04
J 0
(1075 3875);
DISPLAY 0.638298 (1075 3875);
DISPLAY INVISIBLE (1075 3875);
FORCEPROP 1 LAST TOLERANCE 20%
J 0
(1075 3975);
DISPLAY 0.638298 (1075 3975);
FORCEPROP 1 LAST VOLTAGE 4V
J 0
(1075 4025);
DISPLAY 0.638298 (1075 4025);
FORCEPROP 1 LAST PACK_TYPE C0805
J 0
(1075 3825);
DISPLAY 0.638298 (1075 3825);
FORCEPROP 1 LAST VALUE 47UF
J 0
(1075 4075);
DISPLAY 0.638298 (1075 4075);
FORCEPROP 1 LAST MATERIAL X6S
J 0
(1075 3925);
DISPLAY 0.638298 (1075 3925);
FORCEPROP 1 LAST $LOCATION C529
J 0
(1075 4125);
DISPLAY 0.978723 (1075 4125);
FORCEPROP 1 LASTPIN (1025 4125) $PN 1
J 0
(1035 4105);
DISPLAY 0.787234 (1035 4105);
FORCEPROP 1 LASTPIN (1025 3925) $PN 2
J 0
(1035 3905);
DISPLAY 0.787234 (1035 3905);
FORCEPROP 2 LAST CDS_LIB pure_quanta
J 0
(1025 4025);
PAINT MONO (1025 4025);
DISPLAY INVISIBLE (1025 4025);
FORCEPROP 2 LAST CDS_LOCATION C529
J 0
(1075 4225);
DISPLAY 1.021277 (1075 4225);
DISPLAY INVISIBLE (1075 4225);
FORCEPROP 2 LAST $SEC 1
J 0
(1075 4225);
DISPLAY 0.680851 (1075 4225);
PAINT MONO (1075 4225);
DISPLAY INVISIBLE (1075 4225);
FORCEPROP 2 LAST CDS_SEC 1
J 0
(1075 4225);
DISPLAY 1.021277 (1075 4225);
DISPLAY INVISIBLE (1075 4225);
FORCEPROP 1 LAST PATH I41
J 0
(1075 4175);
DISPLAY 0.978723 (1075 4175);
PAINT WHITE (1075 4175);
DISPLAY INVISIBLE (1075 4175);
FORCEADD UNIVERSAL_GND..1
(-2575 7625);
FORCEPROP 3 LASTPIN (-2575 7675) SIG_NAME GND\g
J 0
(-2565 7685);
DISPLAY 0.659574 (-2565 7685);
PAINT MONO (-2565 7685);
DISPLAY INVISIBLE (-2565 7685);
FORCEPROP 2 LAST CDS_LIB logical_power
J 0
(-2575 7625);
PAINT MONO (-2575 7625);
DISPLAY INVISIBLE (-2575 7625);
FORCEPROP 1 LAST HDL_POWER GND
J 1
(-2550 7550);
DISPLAY 0.872340 (-2550 7550);
PAINT GREEN (-2550 7550);
DISPLAY INVISIBLE (-2550 7550);
FORCEPROP 1 LAST PATH I42
J 0
(-2500 7625);
DISPLAY 0.872340 (-2500 7625);
PAINT AQUA (-2500 7625);
DISPLAY INVISIBLE (-2500 7625);
FORCEADD Q_CAP..1
(-2575 7950);
FORCEPROP 1 LAST PART_NUMBER CH647KMEA04
J 0
(-2525 7800);
DISPLAY 0.638298 (-2525 7800);
DISPLAY INVISIBLE (-2525 7800);
FORCEPROP 1 LAST VALUE 47UF
J 0
(-2525 8000);
DISPLAY 0.638298 (-2525 8000);
FORCEPROP 1 LAST TOLERANCE 20%
J 0
(-2525 7900);
DISPLAY 0.638298 (-2525 7900);
FORCEPROP 1 LAST VOLTAGE 4V
J 0
(-2525 7950);
DISPLAY 0.638298 (-2525 7950);
FORCEPROP 1 LAST PACK_TYPE C0805
J 0
(-2525 7750);
DISPLAY 0.638298 (-2525 7750);
FORCEPROP 1 LAST MATERIAL X6S
J 0
(-2525 7850);
DISPLAY 0.638298 (-2525 7850);
FORCEPROP 1 LAST $LOCATION C511
J 0
(-2525 8050);
DISPLAY 0.978723 (-2525 8050);
FORCEPROP 1 LASTPIN (-2575 8050) $PN 1
J 0
(-2565 8030);
DISPLAY 0.787234 (-2565 8030);
FORCEPROP 1 LASTPIN (-2575 7850) $PN 2
J 0
(-2565 7830);
DISPLAY 0.787234 (-2565 7830);
FORCEPROP 2 LAST CDS_LIB pure_quanta
J 0
(-2575 7950);
PAINT MONO (-2575 7950);
DISPLAY INVISIBLE (-2575 7950);
FORCEPROP 2 LAST CDS_LOCATION C511
J 0
(-2525 8150);
DISPLAY 1.021277 (-2525 8150);
DISPLAY INVISIBLE (-2525 8150);
FORCEPROP 2 LAST $SEC 1
J 0
(-2525 8150);
DISPLAY 0.680851 (-2525 8150);
PAINT MONO (-2525 8150);
DISPLAY INVISIBLE (-2525 8150);
FORCEPROP 2 LAST CDS_SEC 1
J 0
(-2525 8150);
DISPLAY 1.021277 (-2525 8150);
DISPLAY INVISIBLE (-2525 8150);
FORCEPROP 1 LAST PATH I43
J 0
(-2525 8100);
DISPLAY 0.978723 (-2525 8100);
PAINT WHITE (-2525 8100);
DISPLAY INVISIBLE (-2525 8100);
FORCEADD Q_CAP..1
(-2575 8825);
FORCEPROP 1 LAST PART_NUMBER CH647KMEA04
J 0
(-2525 8675);
DISPLAY 0.638298 (-2525 8675);
DISPLAY INVISIBLE (-2525 8675);
FORCEPROP 1 LAST TOLERANCE 20%
J 0
(-2525 8775);
DISPLAY 0.638298 (-2525 8775);
FORCEPROP 1 LAST VOLTAGE 4V
J 0
(-2525 8825);
DISPLAY 0.638298 (-2525 8825);
FORCEPROP 1 LAST PACK_TYPE C0805
J 0
(-2525 8625);
DISPLAY 0.638298 (-2525 8625);
FORCEPROP 1 LAST VALUE 47UF
J 0
(-2525 8875);
DISPLAY 0.638298 (-2525 8875);
FORCEPROP 1 LAST MATERIAL X6S
J 0
(-2525 8725);
DISPLAY 0.638298 (-2525 8725);
FORCEPROP 1 LAST $LOCATION C392
J 0
(-2525 8925);
DISPLAY 0.638298 (-2525 8925);
FORCEPROP 1 LASTPIN (-2575 8925) $PN 1
J 0
(-2565 8905);
DISPLAY 0.787234 (-2565 8905);
FORCEPROP 1 LASTPIN (-2575 8725) $PN 2
J 0
(-2565 8705);
DISPLAY 0.787234 (-2565 8705);
FORCEPROP 2 LAST CDS_LIB pure_quanta
J 0
(-2575 8825);
PAINT MONO (-2575 8825);
DISPLAY INVISIBLE (-2575 8825);
FORCEPROP 1 LAST $LOCATION C392
J 0
(-2525 9025);
DISPLAY 1.021277 (-2525 9025);
DISPLAY INVISIBLE (-2525 9025);
FORCEPROP 2 LAST CDS_LOCATION C392
J 0
(-2525 9025);
DISPLAY 1.021277 (-2525 9025);
DISPLAY INVISIBLE (-2525 9025);
FORCEPROP 2 LAST $SEC 1
J 0
(-2525 9025);
DISPLAY 0.680851 (-2525 9025);
PAINT MONO (-2525 9025);
DISPLAY INVISIBLE (-2525 9025);
FORCEPROP 2 LAST CDS_SEC 1
J 0
(-2525 9025);
DISPLAY 1.021277 (-2525 9025);
DISPLAY INVISIBLE (-2525 9025);
FORCEPROP 1 LAST PATH I44
J 0
(-2525 8975);
DISPLAY 0.978723 (-2525 8975);
PAINT WHITE (-2525 8975);
DISPLAY INVISIBLE (-2525 8975);
FORCEADD Q_CAP..1
(-2125 8825);
FORCEPROP 1 LAST PART_NUMBER CH647KMEA04
J 0
(-2075 8675);
DISPLAY 0.638298 (-2075 8675);
DISPLAY INVISIBLE (-2075 8675);
FORCEPROP 1 LAST TOLERANCE 20%
J 0
(-2075 8775);
DISPLAY 0.638298 (-2075 8775);
FORCEPROP 1 LAST VOLTAGE 4V
J 0
(-2075 8825);
DISPLAY 0.638298 (-2075 8825);
FORCEPROP 1 LAST PACK_TYPE C0805
J 0
(-2075 8625);
DISPLAY 0.638298 (-2075 8625);
FORCEPROP 1 LAST VALUE 47UF
J 0
(-2075 8875);
DISPLAY 0.638298 (-2075 8875);
FORCEPROP 1 LAST MATERIAL X6S
J 0
(-2075 8725);
DISPLAY 0.638298 (-2075 8725);
FORCEPROP 1 LAST $LOCATION C394
J 0
(-2075 8925);
DISPLAY 0.638298 (-2075 8925);
FORCEPROP 1 LASTPIN (-2125 8925) $PN 1
J 0
(-2115 8905);
DISPLAY 0.787234 (-2115 8905);
FORCEPROP 1 LASTPIN (-2125 8725) $PN 2
J 0
(-2115 8705);
DISPLAY 0.787234 (-2115 8705);
FORCEPROP 2 LAST CDS_LIB pure_quanta
J 0
(-2125 8825);
PAINT MONO (-2125 8825);
DISPLAY INVISIBLE (-2125 8825);
FORCEPROP 1 LAST $LOCATION C394
J 0
(-2075 9025);
DISPLAY 1.021277 (-2075 9025);
DISPLAY INVISIBLE (-2075 9025);
FORCEPROP 2 LAST CDS_LOCATION C394
J 0
(-2075 9025);
DISPLAY 1.021277 (-2075 9025);
DISPLAY INVISIBLE (-2075 9025);
FORCEPROP 2 LAST $SEC 1
J 0
(-2075 9025);
DISPLAY 0.680851 (-2075 9025);
PAINT MONO (-2075 9025);
DISPLAY INVISIBLE (-2075 9025);
FORCEPROP 2 LAST CDS_SEC 1
J 0
(-2075 9025);
DISPLAY 1.021277 (-2075 9025);
DISPLAY INVISIBLE (-2075 9025);
FORCEPROP 1 LAST PATH I45
J 0
(-2075 8975);
DISPLAY 0.978723 (-2075 8975);
PAINT WHITE (-2075 8975);
DISPLAY INVISIBLE (-2075 8975);
FORCEADD Q_CAP..1
(-1675 8825);
FORCEPROP 1 LAST PART_NUMBER CH647KMEA04
J 0
(-1625 8675);
DISPLAY 0.638298 (-1625 8675);
DISPLAY INVISIBLE (-1625 8675);
FORCEPROP 1 LAST TOLERANCE 20%
J 0
(-1625 8775);
DISPLAY 0.638298 (-1625 8775);
FORCEPROP 1 LAST VOLTAGE 4V
J 0
(-1625 8825);
DISPLAY 0.638298 (-1625 8825);
FORCEPROP 1 LAST PACK_TYPE C0805
J 0
(-1625 8625);
DISPLAY 0.638298 (-1625 8625);
FORCEPROP 1 LAST VALUE 47UF
J 0
(-1625 8875);
DISPLAY 0.638298 (-1625 8875);
FORCEPROP 1 LAST MATERIAL X6S
J 0
(-1625 8725);
DISPLAY 0.638298 (-1625 8725);
FORCEPROP 1 LAST $LOCATION C396
J 0
(-1625 8925);
DISPLAY 0.638298 (-1625 8925);
FORCEPROP 1 LASTPIN (-1675 8925) $PN 1
J 0
(-1665 8905);
DISPLAY 0.787234 (-1665 8905);
FORCEPROP 1 LASTPIN (-1675 8725) $PN 2
J 0
(-1665 8705);
DISPLAY 0.787234 (-1665 8705);
FORCEPROP 2 LAST CDS_LIB pure_quanta
J 0
(-1675 8825);
PAINT MONO (-1675 8825);
DISPLAY INVISIBLE (-1675 8825);
FORCEPROP 1 LAST $LOCATION C396
J 0
(-1625 9025);
DISPLAY 1.021277 (-1625 9025);
DISPLAY INVISIBLE (-1625 9025);
FORCEPROP 2 LAST CDS_LOCATION C396
J 0
(-1625 9025);
DISPLAY 1.021277 (-1625 9025);
DISPLAY INVISIBLE (-1625 9025);
FORCEPROP 2 LAST $SEC 1
J 0
(-1625 9025);
DISPLAY 0.680851 (-1625 9025);
PAINT MONO (-1625 9025);
DISPLAY INVISIBLE (-1625 9025);
FORCEPROP 2 LAST CDS_SEC 1
J 0
(-1625 9025);
DISPLAY 1.021277 (-1625 9025);
DISPLAY INVISIBLE (-1625 9025);
FORCEPROP 1 LAST PATH I46
J 0
(-1625 8975);
DISPLAY 0.978723 (-1625 8975);
PAINT WHITE (-1625 8975);
DISPLAY INVISIBLE (-1625 8975);
FORCEADD Q_CAP..1
(-1225 8825);
FORCEPROP 1 LAST PART_NUMBER CH647KMEA04
J 0
(-1175 8675);
DISPLAY 0.638298 (-1175 8675);
DISPLAY INVISIBLE (-1175 8675);
FORCEPROP 1 LAST TOLERANCE 20%
J 0
(-1175 8775);
DISPLAY 0.638298 (-1175 8775);
FORCEPROP 1 LAST VOLTAGE 4V
J 0
(-1175 8825);
DISPLAY 0.638298 (-1175 8825);
FORCEPROP 1 LAST PACK_TYPE C0805
J 0
(-1175 8625);
DISPLAY 0.638298 (-1175 8625);
FORCEPROP 1 LAST VALUE 47UF
J 0
(-1175 8875);
DISPLAY 0.638298 (-1175 8875);
FORCEPROP 1 LAST MATERIAL X6S
J 0
(-1175 8725);
DISPLAY 0.638298 (-1175 8725);
FORCEPROP 1 LAST $LOCATION C398
J 0
(-1175 8925);
DISPLAY 0.638298 (-1175 8925);
FORCEPROP 1 LASTPIN (-1225 8925) $PN 1
J 0
(-1215 8905);
DISPLAY 0.787234 (-1215 8905);
FORCEPROP 1 LASTPIN (-1225 8725) $PN 2
J 0
(-1215 8705);
DISPLAY 0.787234 (-1215 8705);
FORCEPROP 2 LAST CDS_LIB pure_quanta
J 0
(-1225 8825);
PAINT MONO (-1225 8825);
DISPLAY INVISIBLE (-1225 8825);
FORCEPROP 1 LAST $LOCATION C398
J 0
(-1175 9025);
DISPLAY 1.021277 (-1175 9025);
DISPLAY INVISIBLE (-1175 9025);
FORCEPROP 2 LAST CDS_LOCATION C398
J 0
(-1175 9025);
DISPLAY 1.021277 (-1175 9025);
DISPLAY INVISIBLE (-1175 9025);
FORCEPROP 2 LAST $SEC 1
J 0
(-1175 9025);
DISPLAY 0.680851 (-1175 9025);
PAINT MONO (-1175 9025);
DISPLAY INVISIBLE (-1175 9025);
FORCEPROP 2 LAST CDS_SEC 1
J 0
(-1175 9025);
DISPLAY 1.021277 (-1175 9025);
DISPLAY INVISIBLE (-1175 9025);
FORCEPROP 1 LAST PATH I47
J 0
(-1175 8975);
DISPLAY 0.978723 (-1175 8975);
PAINT WHITE (-1175 8975);
DISPLAY INVISIBLE (-1175 8975);
FORCEADD Q_CAP..1
(-775 8825);
FORCEPROP 1 LAST PART_NUMBER CH647KMEA04
J 0
(-725 8675);
DISPLAY 0.638298 (-725 8675);
DISPLAY INVISIBLE (-725 8675);
FORCEPROP 1 LAST TOLERANCE 20%
J 0
(-725 8775);
DISPLAY 0.638298 (-725 8775);
FORCEPROP 1 LAST VOLTAGE 4V
J 0
(-725 8825);
DISPLAY 0.638298 (-725 8825);
FORCEPROP 1 LAST PACK_TYPE C0805
J 0
(-725 8625);
DISPLAY 0.638298 (-725 8625);
FORCEPROP 1 LAST VALUE 47UF
J 0
(-725 8875);
DISPLAY 0.638298 (-725 8875);
FORCEPROP 1 LAST MATERIAL X6S
J 0
(-725 8725);
DISPLAY 0.638298 (-725 8725);
FORCEPROP 1 LAST $LOCATION C366
J 0
(-725 8925);
DISPLAY 0.638298 (-725 8925);
FORCEPROP 1 LASTPIN (-775 8925) $PN 1
J 0
(-765 8905);
DISPLAY 0.787234 (-765 8905);
FORCEPROP 1 LASTPIN (-775 8725) $PN 2
J 0
(-765 8705);
DISPLAY 0.787234 (-765 8705);
FORCEPROP 2 LAST CDS_LIB pure_quanta
J 0
(-775 8825);
PAINT MONO (-775 8825);
DISPLAY INVISIBLE (-775 8825);
FORCEPROP 1 LAST $LOCATION C366
J 0
(-725 9025);
DISPLAY 1.021277 (-725 9025);
DISPLAY INVISIBLE (-725 9025);
FORCEPROP 2 LAST CDS_LOCATION C366
J 0
(-725 9025);
DISPLAY 1.021277 (-725 9025);
DISPLAY INVISIBLE (-725 9025);
FORCEPROP 2 LAST $SEC 1
J 0
(-725 9025);
DISPLAY 0.680851 (-725 9025);
PAINT MONO (-725 9025);
DISPLAY INVISIBLE (-725 9025);
FORCEPROP 2 LAST CDS_SEC 1
J 0
(-725 9025);
DISPLAY 1.021277 (-725 9025);
DISPLAY INVISIBLE (-725 9025);
FORCEPROP 1 LAST PATH I48
J 0
(-725 8975);
DISPLAY 0.978723 (-725 8975);
PAINT WHITE (-725 8975);
DISPLAY INVISIBLE (-725 8975);
FORCEADD Q_CAP..1
(-325 8825);
FORCEPROP 1 LAST PART_NUMBER CH647KMEA04
J 0
(-275 8675);
DISPLAY 0.638298 (-275 8675);
DISPLAY INVISIBLE (-275 8675);
FORCEPROP 1 LAST TOLERANCE 20%
J 0
(-275 8775);
DISPLAY 0.638298 (-275 8775);
FORCEPROP 1 LAST VOLTAGE 4V
J 0
(-275 8825);
DISPLAY 0.638298 (-275 8825);
FORCEPROP 1 LAST PACK_TYPE C0805
J 0
(-275 8625);
DISPLAY 0.638298 (-275 8625);
FORCEPROP 1 LAST VALUE 47UF
J 0
(-275 8875);
DISPLAY 0.638298 (-275 8875);
FORCEPROP 1 LAST MATERIAL X6S
J 0
(-275 8725);
DISPLAY 0.638298 (-275 8725);
FORCEPROP 1 LAST $LOCATION C369
J 0
(-275 8925);
DISPLAY 0.638298 (-275 8925);
FORCEPROP 1 LASTPIN (-325 8925) $PN 1
J 0
(-315 8905);
DISPLAY 0.787234 (-315 8905);
FORCEPROP 1 LASTPIN (-325 8725) $PN 2
J 0
(-315 8705);
DISPLAY 0.787234 (-315 8705);
FORCEPROP 2 LAST CDS_LIB pure_quanta
J 0
(-325 8825);
PAINT MONO (-325 8825);
DISPLAY INVISIBLE (-325 8825);
FORCEPROP 1 LAST $LOCATION C369
J 0
(-275 9025);
DISPLAY 1.021277 (-275 9025);
DISPLAY INVISIBLE (-275 9025);
FORCEPROP 2 LAST CDS_LOCATION C369
J 0
(-275 9025);
DISPLAY 1.021277 (-275 9025);
DISPLAY INVISIBLE (-275 9025);
FORCEPROP 2 LAST $SEC 1
J 0
(-275 9025);
DISPLAY 0.680851 (-275 9025);
PAINT MONO (-275 9025);
DISPLAY INVISIBLE (-275 9025);
FORCEPROP 2 LAST CDS_SEC 1
J 0
(-275 9025);
DISPLAY 1.021277 (-275 9025);
DISPLAY INVISIBLE (-275 9025);
FORCEPROP 1 LAST PATH I49
J 0
(-275 8975);
DISPLAY 0.978723 (-275 8975);
PAINT WHITE (-275 8975);
DISPLAY INVISIBLE (-275 8975);
FORCEADD Q_CAP..1
(-3925 5075);
FORCEPROP 1 LAST PART_NUMBER CH647KMEA04
J 0
(-3875 4925);
DISPLAY 0.638298 (-3875 4925);
DISPLAY INVISIBLE (-3875 4925);
FORCEPROP 1 LAST MATERIAL X6S
J 0
(-3875 4975);
DISPLAY 0.638298 (-3875 4975);
FORCEPROP 1 LAST TOLERANCE 20%
J 0
(-3875 5025);
DISPLAY 0.638298 (-3875 5025);
FORCEPROP 1 LAST VOLTAGE 4V
J 0
(-3875 5075);
DISPLAY 0.638298 (-3875 5075);
FORCEPROP 1 LAST PACK_TYPE C0805
J 0
(-3875 4875);
DISPLAY 0.638298 (-3875 4875);
FORCEPROP 1 LAST VALUE 47UF
J 0
(-3875 5125);
DISPLAY 0.638298 (-3875 5125);
FORCEPROP 1 LAST $LOCATION C525
J 0
(-3875 5175);
DISPLAY 0.978723 (-3875 5175);
FORCEPROP 1 LASTPIN (-3925 5175) $PN 1
J 0
(-3915 5155);
DISPLAY 0.787234 (-3915 5155);
FORCEPROP 1 LASTPIN (-3925 4975) $PN 2
J 0
(-3915 4955);
DISPLAY 0.787234 (-3915 4955);
FORCEPROP 2 LAST CDS_LIB pure_quanta
J 0
(-3925 5075);
PAINT MONO (-3925 5075);
DISPLAY INVISIBLE (-3925 5075);
FORCEPROP 2 LAST CDS_LOCATION C525
J 0
(-3875 5275);
DISPLAY 1.021277 (-3875 5275);
DISPLAY INVISIBLE (-3875 5275);
FORCEPROP 2 LAST $SEC 1
J 0
(-3875 5275);
DISPLAY 0.680851 (-3875 5275);
PAINT MONO (-3875 5275);
DISPLAY INVISIBLE (-3875 5275);
FORCEPROP 2 LAST CDS_SEC 1
J 0
(-3875 5275);
DISPLAY 1.021277 (-3875 5275);
DISPLAY INVISIBLE (-3875 5275);
FORCEPROP 1 LAST PATH I5
J 0
(-3875 5225);
DISPLAY 0.978723 (-3875 5225);
PAINT WHITE (-3875 5225);
DISPLAY INVISIBLE (-3875 5225);
FORCEADD Q_CAP..1
(125 8825);
FORCEPROP 1 LAST PART_NUMBER CH647KMEA04
J 0
(175 8675);
DISPLAY 0.638298 (175 8675);
DISPLAY INVISIBLE (175 8675);
FORCEPROP 1 LAST TOLERANCE 20%
J 0
(175 8775);
DISPLAY 0.638298 (175 8775);
FORCEPROP 1 LAST VOLTAGE 4V
J 0
(175 8825);
DISPLAY 0.638298 (175 8825);
FORCEPROP 1 LAST PACK_TYPE C0805
J 0
(175 8625);
DISPLAY 0.638298 (175 8625);
FORCEPROP 1 LAST VALUE 47UF
J 0
(175 8875);
DISPLAY 0.638298 (175 8875);
FORCEPROP 1 LAST MATERIAL X6S
J 0
(175 8725);
DISPLAY 0.638298 (175 8725);
FORCEPROP 1 LAST $LOCATION C372
J 0
(175 8925);
DISPLAY 0.638298 (175 8925);
FORCEPROP 1 LASTPIN (125 8925) $PN 1
J 0
(135 8905);
DISPLAY 0.787234 (135 8905);
FORCEPROP 1 LASTPIN (125 8725) $PN 2
J 0
(135 8705);
DISPLAY 0.787234 (135 8705);
FORCEPROP 2 LAST CDS_LIB pure_quanta
J 0
(125 8825);
PAINT MONO (125 8825);
DISPLAY INVISIBLE (125 8825);
FORCEPROP 1 LAST $LOCATION C372
J 0
(175 9025);
DISPLAY 1.021277 (175 9025);
DISPLAY INVISIBLE (175 9025);
FORCEPROP 2 LAST CDS_LOCATION C372
J 0
(175 9025);
DISPLAY 1.021277 (175 9025);
DISPLAY INVISIBLE (175 9025);
FORCEPROP 2 LAST $SEC 1
J 0
(175 9025);
DISPLAY 0.680851 (175 9025);
PAINT MONO (175 9025);
DISPLAY INVISIBLE (175 9025);
FORCEPROP 2 LAST CDS_SEC 1
J 0
(175 9025);
DISPLAY 1.021277 (175 9025);
DISPLAY INVISIBLE (175 9025);
FORCEPROP 1 LAST PATH I50
J 0
(175 8975);
DISPLAY 0.978723 (175 8975);
PAINT WHITE (175 8975);
DISPLAY INVISIBLE (175 8975);
FORCEADD Q_CAP..1
(575 8825);
FORCEPROP 1 LAST PART_NUMBER CH647KMEA04
J 0
(625 8675);
DISPLAY 0.638298 (625 8675);
DISPLAY INVISIBLE (625 8675);
FORCEPROP 1 LAST TOLERANCE 20%
J 0
(625 8775);
DISPLAY 0.638298 (625 8775);
FORCEPROP 1 LAST VOLTAGE 4V
J 0
(625 8825);
DISPLAY 0.638298 (625 8825);
FORCEPROP 1 LAST PACK_TYPE C0805
J 0
(625 8625);
DISPLAY 0.638298 (625 8625);
FORCEPROP 1 LAST VALUE 47UF
J 0
(625 8875);
DISPLAY 0.638298 (625 8875);
FORCEPROP 1 LAST MATERIAL X6S
J 0
(625 8725);
DISPLAY 0.638298 (625 8725);
FORCEPROP 1 LAST $LOCATION C374
J 0
(625 8925);
DISPLAY 0.638298 (625 8925);
FORCEPROP 1 LASTPIN (575 8925) $PN 1
J 0
(585 8905);
DISPLAY 0.787234 (585 8905);
FORCEPROP 1 LASTPIN (575 8725) $PN 2
J 0
(585 8705);
DISPLAY 0.787234 (585 8705);
FORCEPROP 2 LAST CDS_LIB pure_quanta
J 0
(575 8825);
PAINT MONO (575 8825);
DISPLAY INVISIBLE (575 8825);
FORCEPROP 1 LAST $LOCATION C374
J 0
(625 9025);
DISPLAY 1.021277 (625 9025);
DISPLAY INVISIBLE (625 9025);
FORCEPROP 2 LAST CDS_LOCATION C374
J 0
(625 9025);
DISPLAY 1.021277 (625 9025);
DISPLAY INVISIBLE (625 9025);
FORCEPROP 2 LAST $SEC 1
J 0
(625 9025);
DISPLAY 0.680851 (625 9025);
PAINT MONO (625 9025);
DISPLAY INVISIBLE (625 9025);
FORCEPROP 2 LAST CDS_SEC 1
J 0
(625 9025);
DISPLAY 1.021277 (625 9025);
DISPLAY INVISIBLE (625 9025);
FORCEPROP 1 LAST PATH I51
J 0
(625 8975);
DISPLAY 0.978723 (625 8975);
PAINT WHITE (625 8975);
DISPLAY INVISIBLE (625 8975);
FORCEADD Q_CAP..1
(1025 8825);
FORCEPROP 1 LAST PART_NUMBER CH647KMEA04
J 0
(1075 8675);
DISPLAY 0.638298 (1075 8675);
DISPLAY INVISIBLE (1075 8675);
FORCEPROP 1 LAST TOLERANCE 20%
J 0
(1075 8775);
DISPLAY 0.638298 (1075 8775);
FORCEPROP 1 LAST VOLTAGE 4V
J 0
(1075 8825);
DISPLAY 0.638298 (1075 8825);
FORCEPROP 1 LAST PACK_TYPE C0805
J 0
(1075 8625);
DISPLAY 0.638298 (1075 8625);
FORCEPROP 1 LAST VALUE 47UF
J 0
(1075 8875);
DISPLAY 0.638298 (1075 8875);
FORCEPROP 1 LAST MATERIAL X6S
J 0
(1075 8725);
DISPLAY 0.638298 (1075 8725);
FORCEPROP 1 LAST $LOCATION C377
J 0
(1075 8925);
DISPLAY 0.638298 (1075 8925);
FORCEPROP 1 LASTPIN (1025 8925) $PN 1
J 0
(1035 8905);
DISPLAY 0.787234 (1035 8905);
FORCEPROP 1 LASTPIN (1025 8725) $PN 2
J 0
(1035 8705);
DISPLAY 0.787234 (1035 8705);
FORCEPROP 2 LAST CDS_LIB pure_quanta
J 0
(1025 8825);
PAINT MONO (1025 8825);
DISPLAY INVISIBLE (1025 8825);
FORCEPROP 1 LAST $LOCATION C377
J 0
(1075 9025);
DISPLAY 1.021277 (1075 9025);
DISPLAY INVISIBLE (1075 9025);
FORCEPROP 2 LAST CDS_LOCATION C377
J 0
(1075 9025);
DISPLAY 1.021277 (1075 9025);
DISPLAY INVISIBLE (1075 9025);
FORCEPROP 2 LAST $SEC 1
J 0
(1075 9025);
DISPLAY 0.680851 (1075 9025);
PAINT MONO (1075 9025);
DISPLAY INVISIBLE (1075 9025);
FORCEPROP 2 LAST CDS_SEC 1
J 0
(1075 9025);
DISPLAY 1.021277 (1075 9025);
DISPLAY INVISIBLE (1075 9025);
FORCEPROP 1 LAST PATH I52
J 0
(1075 8975);
DISPLAY 0.978723 (1075 8975);
PAINT WHITE (1075 8975);
DISPLAY INVISIBLE (1075 8975);
FORCEADD Q_CAP..1
(1475 8825);
FORCEPROP 1 LAST PART_NUMBER CH647KMEA04
J 0
(1525 8675);
DISPLAY 0.638298 (1525 8675);
DISPLAY INVISIBLE (1525 8675);
FORCEPROP 1 LAST TOLERANCE 20%
J 0
(1525 8775);
DISPLAY 0.638298 (1525 8775);
FORCEPROP 1 LAST VOLTAGE 4V
J 0
(1525 8825);
DISPLAY 0.638298 (1525 8825);
FORCEPROP 1 LAST PACK_TYPE C0805
J 0
(1525 8625);
DISPLAY 0.638298 (1525 8625);
FORCEPROP 1 LAST VALUE 47UF
J 0
(1525 8875);
DISPLAY 0.638298 (1525 8875);
FORCEPROP 1 LAST MATERIAL X6S
J 0
(1525 8725);
DISPLAY 0.638298 (1525 8725);
FORCEPROP 1 LAST $LOCATION C380
J 0
(1525 8925);
DISPLAY 0.638298 (1525 8925);
FORCEPROP 1 LASTPIN (1475 8925) $PN 1
J 0
(1485 8905);
DISPLAY 0.787234 (1485 8905);
FORCEPROP 1 LASTPIN (1475 8725) $PN 2
J 0
(1485 8705);
DISPLAY 0.787234 (1485 8705);
FORCEPROP 2 LAST CDS_LIB pure_quanta
J 0
(1475 8825);
PAINT MONO (1475 8825);
DISPLAY INVISIBLE (1475 8825);
FORCEPROP 1 LAST $LOCATION C380
J 0
(1525 9025);
DISPLAY 1.021277 (1525 9025);
DISPLAY INVISIBLE (1525 9025);
FORCEPROP 2 LAST CDS_LOCATION C380
J 0
(1525 9025);
DISPLAY 1.021277 (1525 9025);
DISPLAY INVISIBLE (1525 9025);
FORCEPROP 2 LAST $SEC 1
J 0
(1525 9025);
DISPLAY 0.680851 (1525 9025);
PAINT MONO (1525 9025);
DISPLAY INVISIBLE (1525 9025);
FORCEPROP 2 LAST CDS_SEC 1
J 0
(1525 9025);
DISPLAY 1.021277 (1525 9025);
DISPLAY INVISIBLE (1525 9025);
FORCEPROP 1 LAST PATH I53
J 0
(1525 8975);
DISPLAY 0.978723 (1525 8975);
PAINT WHITE (1525 8975);
DISPLAY INVISIBLE (1525 8975);
FORCEADD Q_CAP..1
(1925 8825);
FORCEPROP 1 LAST PART_NUMBER CH647KMEA04
J 0
(1975 8675);
DISPLAY 0.638298 (1975 8675);
DISPLAY INVISIBLE (1975 8675);
FORCEPROP 1 LAST TOLERANCE 20%
J 0
(1975 8775);
DISPLAY 0.638298 (1975 8775);
FORCEPROP 1 LAST VOLTAGE 4V
J 0
(1975 8825);
DISPLAY 0.638298 (1975 8825);
FORCEPROP 1 LAST PACK_TYPE C0805
J 0
(1975 8625);
DISPLAY 0.638298 (1975 8625);
FORCEPROP 1 LAST VALUE 47UF
J 0
(1975 8875);
DISPLAY 0.638298 (1975 8875);
FORCEPROP 1 LAST MATERIAL X6S
J 0
(1975 8725);
DISPLAY 0.638298 (1975 8725);
FORCEPROP 1 LAST $LOCATION C383
J 0
(1975 8925);
DISPLAY 0.638298 (1975 8925);
FORCEPROP 1 LASTPIN (1925 8925) $PN 1
J 0
(1935 8905);
DISPLAY 0.787234 (1935 8905);
FORCEPROP 1 LASTPIN (1925 8725) $PN 2
J 0
(1935 8705);
DISPLAY 0.787234 (1935 8705);
FORCEPROP 2 LAST CDS_LIB pure_quanta
J 0
(1925 8825);
PAINT MONO (1925 8825);
DISPLAY INVISIBLE (1925 8825);
FORCEPROP 1 LAST $LOCATION C383
J 0
(1975 9025);
DISPLAY 1.021277 (1975 9025);
DISPLAY INVISIBLE (1975 9025);
FORCEPROP 2 LAST CDS_LOCATION C383
J 0
(1975 9025);
DISPLAY 1.021277 (1975 9025);
DISPLAY INVISIBLE (1975 9025);
FORCEPROP 2 LAST $SEC 1
J 0
(1975 9025);
DISPLAY 0.680851 (1975 9025);
PAINT MONO (1975 9025);
DISPLAY INVISIBLE (1975 9025);
FORCEPROP 2 LAST CDS_SEC 1
J 0
(1975 9025);
DISPLAY 1.021277 (1975 9025);
DISPLAY INVISIBLE (1975 9025);
FORCEPROP 1 LAST PATH I54
J 0
(1975 8975);
DISPLAY 0.978723 (1975 8975);
PAINT WHITE (1975 8975);
DISPLAY INVISIBLE (1975 8975);
FORCEADD UNIVERSAL_GND..1
(1925 8475);
FORCEPROP 3 LASTPIN (1925 8525) SIG_NAME GND\g
J 0
(1935 8535);
DISPLAY 0.659574 (1935 8535);
PAINT MONO (1935 8535);
DISPLAY INVISIBLE (1935 8535);
FORCEPROP 2 LAST CDS_LIB logical_power
J 0
(1925 8475);
PAINT MONO (1925 8475);
DISPLAY INVISIBLE (1925 8475);
FORCEPROP 1 LAST HDL_POWER GND
J 1
(1950 8400);
DISPLAY 0.872340 (1950 8400);
PAINT GREEN (1950 8400);
DISPLAY INVISIBLE (1950 8400);
FORCEPROP 1 LAST PATH I55
J 0
(2000 8475);
DISPLAY 0.872340 (2000 8475);
PAINT AQUA (2000 8475);
DISPLAY INVISIBLE (2000 8475);
FORCEADD Q_CAP..1
(-3475 5075);
FORCEPROP 1 LAST PART_NUMBER CH647KMEA04
J 0
(-3425 4925);
DISPLAY 0.638298 (-3425 4925);
DISPLAY INVISIBLE (-3425 4925);
FORCEPROP 1 LAST TOLERANCE 20%
J 0
(-3425 5025);
DISPLAY 0.638298 (-3425 5025);
FORCEPROP 1 LAST VOLTAGE 4V
J 0
(-3425 5075);
DISPLAY 0.638298 (-3425 5075);
FORCEPROP 1 LAST PACK_TYPE C0805
J 0
(-3425 4875);
DISPLAY 0.638298 (-3425 4875);
FORCEPROP 1 LAST VALUE 47UF
J 0
(-3425 5125);
DISPLAY 0.638298 (-3425 5125);
FORCEPROP 1 LAST MATERIAL X6S
J 0
(-3425 4975);
DISPLAY 0.638298 (-3425 4975);
FORCEPROP 1 LAST $LOCATION C528
J 0
(-3425 5175);
DISPLAY 0.978723 (-3425 5175);
FORCEPROP 1 LASTPIN (-3475 5175) $PN 1
J 0
(-3465 5155);
DISPLAY 0.787234 (-3465 5155);
FORCEPROP 1 LASTPIN (-3475 4975) $PN 2
J 0
(-3465 4955);
DISPLAY 0.787234 (-3465 4955);
FORCEPROP 2 LAST CDS_LIB pure_quanta
J 0
(-3475 5075);
PAINT MONO (-3475 5075);
DISPLAY INVISIBLE (-3475 5075);
FORCEPROP 2 LAST CDS_LOCATION C528
J 0
(-3425 5275);
DISPLAY 1.021277 (-3425 5275);
DISPLAY INVISIBLE (-3425 5275);
FORCEPROP 2 LAST $SEC 1
J 0
(-3425 5275);
DISPLAY 0.680851 (-3425 5275);
PAINT MONO (-3425 5275);
DISPLAY INVISIBLE (-3425 5275);
FORCEPROP 2 LAST CDS_SEC 1
J 0
(-3425 5275);
DISPLAY 1.021277 (-3425 5275);
DISPLAY INVISIBLE (-3425 5275);
FORCEPROP 1 LAST PATH I6
J 0
(-3425 5225);
DISPLAY 0.978723 (-3425 5225);
PAINT WHITE (-3425 5225);
DISPLAY INVISIBLE (-3425 5225);
FORCEADD Q_CAP..1
(-3025 5075);
FORCEPROP 1 LAST PART_NUMBER CH647KMEA04
J 0
(-2975 4925);
DISPLAY 0.638298 (-2975 4925);
DISPLAY INVISIBLE (-2975 4925);
FORCEPROP 1 LAST PACK_TYPE C0805
J 0
(-2975 4875);
DISPLAY 0.638298 (-2975 4875);
FORCEPROP 1 LAST VOLTAGE 4V
J 0
(-2975 5075);
DISPLAY 0.638298 (-2975 5075);
FORCEPROP 1 LAST MATERIAL X6S
J 0
(-2975 4975);
DISPLAY 0.638298 (-2975 4975);
FORCEPROP 1 LAST VALUE 47UF
J 0
(-2975 5125);
DISPLAY 0.638298 (-2975 5125);
FORCEPROP 1 LAST TOLERANCE 20%
J 0
(-2975 5025);
DISPLAY 0.638298 (-2975 5025);
FORCEPROP 1 LAST $LOCATION C530
J 0
(-2975 5175);
DISPLAY 0.978723 (-2975 5175);
FORCEPROP 1 LASTPIN (-3025 5175) $PN 1
J 0
(-3015 5155);
DISPLAY 0.787234 (-3015 5155);
FORCEPROP 1 LASTPIN (-3025 4975) $PN 2
J 0
(-3015 4955);
DISPLAY 0.787234 (-3015 4955);
FORCEPROP 2 LAST CDS_LIB pure_quanta
J 0
(-3025 5075);
PAINT MONO (-3025 5075);
DISPLAY INVISIBLE (-3025 5075);
FORCEPROP 2 LAST CDS_LOCATION C530
J 0
(-2975 5275);
DISPLAY 1.021277 (-2975 5275);
DISPLAY INVISIBLE (-2975 5275);
FORCEPROP 2 LAST $SEC 1
J 0
(-2975 5275);
DISPLAY 0.680851 (-2975 5275);
PAINT MONO (-2975 5275);
DISPLAY INVISIBLE (-2975 5275);
FORCEPROP 2 LAST CDS_SEC 1
J 0
(-2975 5275);
DISPLAY 1.021277 (-2975 5275);
DISPLAY INVISIBLE (-2975 5275);
FORCEPROP 1 LAST PATH I7
J 0
(-2975 5225);
DISPLAY 0.978723 (-2975 5225);
PAINT WHITE (-2975 5225);
DISPLAY INVISIBLE (-2975 5225);
FORCEADD UNIVERSAL_POWER..1
(-3925 5350);
FORCEPROP 3 LASTPIN (-3925 5300) SIG_NAME PVCCINFAON_CPU0\g
J 0
(-3915 5310);
DISPLAY 0.659574 (-3915 5310);
PAINT MONO (-3915 5310);
DISPLAY INVISIBLE (-3915 5310);
FORCEPROP 1 LAST HDL_POWER PVCCINFAON_CPU0
J 1
(-3650 5400);
DISPLAY 0.872340 (-3650 5400);
PAINT GREEN (-3650 5400);
FORCEPROP 2 LAST CDS_LIB logical_power
J 0
(-3925 5350);
PAINT MONO (-3925 5350);
DISPLAY INVISIBLE (-3925 5350);
FORCEPROP 1 LAST PATH I8
J 0
(-3875 5375);
DISPLAY 0.872340 (-3875 5375);
PAINT AQUA (-3875 5375);
DISPLAY INVISIBLE (-3875 5375);
FORCEADD Q_CAP..1
(-3925 6100);
FORCEPROP 1 LAST PART_NUMBER CH647KMEA04
J 0
(-3875 5950);
DISPLAY 0.638298 (-3875 5950);
DISPLAY INVISIBLE (-3875 5950);
FORCEPROP 1 LAST VALUE 47UF
J 0
(-3875 6150);
DISPLAY 0.638298 (-3875 6150);
FORCEPROP 1 LAST TOLERANCE 20%
J 0
(-3875 6050);
DISPLAY 0.638298 (-3875 6050);
FORCEPROP 1 LAST VOLTAGE 4V
J 0
(-3875 6100);
DISPLAY 0.638298 (-3875 6100);
FORCEPROP 1 LAST PACK_TYPE C0805
J 0
(-3875 5900);
DISPLAY 0.638298 (-3875 5900);
FORCEPROP 1 LAST MATERIAL X6S
J 0
(-3875 6000);
DISPLAY 0.638298 (-3875 6000);
FORCEPROP 1 LAST $LOCATION C500
J 0
(-3875 6200);
DISPLAY 0.978723 (-3875 6200);
FORCEPROP 1 LASTPIN (-3925 6200) $PN 1
J 0
(-3915 6180);
DISPLAY 0.787234 (-3915 6180);
FORCEPROP 1 LASTPIN (-3925 6000) $PN 2
J 0
(-3915 5980);
DISPLAY 0.787234 (-3915 5980);
FORCEPROP 2 LAST CDS_LIB pure_quanta
J 0
(-3925 6100);
PAINT MONO (-3925 6100);
DISPLAY INVISIBLE (-3925 6100);
FORCEPROP 2 LAST CDS_LOCATION C500
J 0
(-3875 6300);
DISPLAY 1.021277 (-3875 6300);
DISPLAY INVISIBLE (-3875 6300);
FORCEPROP 2 LAST $SEC 1
J 0
(-3875 6300);
DISPLAY 0.680851 (-3875 6300);
PAINT MONO (-3875 6300);
DISPLAY INVISIBLE (-3875 6300);
FORCEPROP 2 LAST CDS_SEC 1
J 0
(-3875 6300);
DISPLAY 1.021277 (-3875 6300);
DISPLAY INVISIBLE (-3875 6300);
FORCEPROP 1 LAST PATH I9
J 0
(-3875 6250);
DISPLAY 0.978723 (-3875 6250);
PAINT WHITE (-3875 6250);
DISPLAY INVISIBLE (-3875 6250);
FORCEADD QUANTA_TITLE_BLOCK_C..1
(5125 2925);
FORCEPROP 0 LAST CDS_CON_LAST_MODIFIED Fri Aug 25 14:00:56 2023
J 0
(3240 2940);
PAINT MONO (3240 2940);
DISPLAY INVISIBLE (3240 2940);
FORCEPROP 2 LAST CUSTOM_TXT_CDS <XR_PAGE_TITLE>
J 0
(-2765 8175);
DISPLAY 0.638298 (-2765 8175);
PAINT PINK (-2765 8175);
DISPLAY INVISIBLE (-2765 8175);
FORCEPROP 2 LAST CUSTOM_TXT_CDS <Q_NUMBER>
J 0
(3722 3028);
DISPLAY 1.212766 (3722 3028);
FORCEPROP 2 LAST CUSTOM_TXT_CDS <CON_LAST_MODIFIED>
J 0
(3240 2940);
DISPLAY 0.978723 (3240 2940);
FORCEPROP 2 LAST CUSTOM_TXT_CDS <Q_PROJ>
J 0
(2743 3027);
DISPLAY 1.212766 (2743 3027);
FORCEPROP 2 LAST CUSTOM_TXT_CDS <Q_REV>
J 0
(4941 3028);
DISPLAY 1.212766 (4941 3028);
FORCEPROP 2 LAST CUSTOM_TXT_CDS <NAME_1>
J 0
(1950 3100);
FORCEPROP 2 LAST CUSTOM_TXT_CDS <NAME_2>
J 0
(1950 2975);
FORCEPROP 1 LAST CUSTOM_TXT_CDS <CON_PAGE_NUM> OF <CON_TOTAL_PAGES>
J 0
(4679 2943);
DISPLAY 0.978723 (4679 2943);
FORCEPROP 1 LAST Q_TITLE SPR CPU0 BOTTOM DECOUPLING CAPS CONTI.
J 0
(-4216 2951);
DISPLAY 1.957447 (-4216 2951);
PAINT GREEN (-4216 2951);
FORCEPROP 1 LAST Q_DEPT 
J 1
(1362 2974);
DISPLAY 1.957447 (1362 2974);
PAINT GREEN (1362 2974);
FORCEPROP 1 LAST COMMENT_BODY TRUE
J 0
(5137 2912);
DISPLAY 0.978723 (5137 2912);
PAINT GREEN (5137 2912);
DISPLAY INVISIBLE (5137 2912);
FORCEPROP 2 LAST CDS_XR_PAGE_TITLE CR-76 : @S9S_MB_2U_LIB.S9S_MB_2U(SCH_1):PAGE76
J 0
(-2765 8175);
DISPLAY 0.638298 (-2765 8175);
PAINT PINK (-2765 8175);
DISPLAY INVISIBLE (-2765 8175);
FORCEPROP 2 LAST CDS_LIB pure_quanta
J 0
(5125 2925);
PAINT MONO (5125 2925);
DISPLAY INVISIBLE (5125 2925);
FORCEPROP 1 LAST CDS_LMAN_SYM_OUTLINE -9475,6775,100,-125
J 0
(5125 2925);
DISPLAY 0.468085 (5125 2925);
PAINT GREEN (5125 2925);
DISPLAY INVISIBLE (5125 2925);
FORCEPROP 2 LAST PAGE_BORDER TRUE
J 0
(-2765 8175);
DISPLAY 0.638298 (-2765 8175);
PAINT PINK (-2765 8175);
DISPLAY INVISIBLE (-2765 8175);
WIRE 16 -1 (-3925 6275)(-3925 6325);
WIRE 16 -1 (-3475 6275)(-3925 6275);
WIRE 16 -1 (-3925 6200)(-3925 6275);
WIRE 16 -1 (-3925 4200)(-3925 4250);
WIRE 16 -1 (-3475 4200)(-3925 4200);
WIRE 16 -1 (-3925 4200)(-3925 4125);
WIRE 16 -1 (-3925 5250)(-3925 5300);
WIRE 16 -1 (-3475 5250)(-3925 5250);
WIRE 16 -1 (-3925 5175)(-3925 5250);
WIRE 16 -1 (-3925 7275)(-3925 7325);
WIRE 16 -1 (-3475 7275)(-3925 7275);
WIRE 16 -1 (-3925 7275)(-3925 7200);
WIRE 16 -1 (-3925 8125)(-3925 8175);
WIRE 16 -1 (-3475 8125)(-3925 8125);
WIRE 16 -1 (-3925 8125)(-3925 8050);
WIRE 16 -1 (-3925 9000)(-3925 9050);
WIRE 16 -1 (-3475 9000)(-3925 9000);
WIRE 16 -1 (-3925 9000)(-3925 8925);
WIRE 16 -1 (-3075 6800)(-3075 6875);
WIRE 16 -1 (-2575 4775)(-2575 4850);
WIRE 16 -1 (-1675 5800)(-1675 5875);
WIRE 16 -1 (1025 3725)(1025 3800);
WIRE 16 -1 (-2575 7675)(-2575 7725);
WIRE 16 -1 (1925 8525)(1925 8600);
WIRE 16 -1 (-3475 4125)(-3475 4200);
WIRE 16 -1 (-3025 4200)(-3475 4200);
WIRE 16 -1 (-3025 4200)(-3025 4125);
WIRE 16 -1 (-2575 4200)(-3025 4200);
WIRE 16 -1 (-2575 4125)(-2575 4200);
WIRE 16 -1 (-2125 4200)(-2575 4200);
WIRE 16 -1 (-2125 4125)(-2125 4200);
WIRE 16 -1 (-1675 4200)(-2125 4200);
WIRE 16 -1 (-1675 4200)(-1675 4125);
WIRE 16 -1 (-1225 4200)(-1675 4200);
WIRE 16 -1 (-1225 4125)(-1225 4200);
WIRE 16 -1 (-775 4200)(-1225 4200);
WIRE 16 -1 (-775 4200)(-775 4125);
WIRE 16 -1 (-325 4200)(-775 4200);
WIRE 16 -1 (-325 4125)(-325 4200);
WIRE 16 -1 (125 4200)(-325 4200);
WIRE 16 -1 (125 4125)(125 4200);
WIRE 16 -1 (575 4200)(125 4200);
WIRE 16 -1 (575 4200)(575 4125);
WIRE 16 -1 (1025 4200)(575 4200);
WIRE 16 -1 (1025 4200)(1025 4125);
WIRE 16 -1 (-3925 4850)(-3925 4975);
WIRE 16 -1 (-3475 4850)(-3925 4850);
WIRE 16 -1 (-3475 4850)(-3475 4975);
WIRE 16 -1 (-3025 4850)(-3475 4850);
WIRE 16 -1 (-3025 4850)(-3025 4975);
WIRE 16 -1 (-2575 4850)(-3025 4850);
WIRE 16 -1 (-2575 4850)(-2575 4975);
WIRE 16 -1 (-3475 5175)(-3475 5250);
WIRE 16 -1 (-3025 5250)(-3475 5250);
WIRE 16 -1 (-3025 5175)(-3025 5250);
WIRE 16 -1 (-2575 5250)(-3025 5250);
WIRE 16 -1 (-2575 5250)(-2575 5175);
WIRE 16 -1 (-3925 5875)(-3925 6000);
WIRE 16 -1 (-3925 5875)(-3475 5875);
WIRE 16 -1 (-3475 5875)(-3475 6000);
WIRE 16 -1 (-3025 5875)(-3475 5875);
WIRE 16 -1 (-3025 5875)(-3025 6000);
WIRE 16 -1 (-2575 5875)(-3025 5875);
WIRE 16 -1 (-2575 5875)(-2575 6000);
WIRE 16 -1 (-2125 5875)(-2575 5875);
WIRE 16 -1 (-2125 5875)(-2125 6000);
WIRE 16 -1 (-1675 5875)(-2125 5875);
WIRE 16 -1 (-1675 5875)(-1675 6000);
WIRE 16 -1 (-3925 8600)(-3925 8725);
WIRE 16 -1 (-3475 8600)(-3925 8600);
WIRE 16 -1 (-3475 8600)(-3475 8725);
WIRE 16 -1 (-3025 8600)(-3475 8600);
WIRE 16 -1 (-3025 8600)(-3025 8725);
WIRE 16 -1 (-2575 8600)(-3025 8600);
WIRE 16 -1 (-2575 8600)(-2575 8725);
WIRE 16 -1 (-2125 8600)(-2575 8600);
WIRE 16 -1 (-2125 8600)(-2125 8725);
WIRE 16 -1 (-1675 8600)(-2125 8600);
WIRE 16 -1 (-1675 8600)(-1675 8725);
WIRE 16 -1 (-1225 8600)(-1675 8600);
WIRE 16 -1 (-1225 8600)(-1225 8725);
WIRE 16 -1 (-775 8600)(-1225 8600);
WIRE 16 -1 (-775 8600)(-775 8725);
WIRE 16 -1 (-325 8600)(-775 8600);
WIRE 16 -1 (-325 8600)(-325 8725);
WIRE 16 -1 (125 8600)(-325 8600);
WIRE 16 -1 (125 8600)(125 8725);
WIRE 16 -1 (575 8600)(125 8600);
WIRE 16 -1 (575 8600)(575 8725);
WIRE 16 -1 (1025 8600)(575 8600);
WIRE 16 -1 (1025 8600)(1025 8725);
WIRE 16 -1 (1475 8600)(1025 8600);
WIRE 16 -1 (1475 8600)(1475 8725);
WIRE 16 -1 (1925 8600)(1475 8600);
WIRE 16 -1 (1925 8600)(1925 8725);
WIRE 16 -1 (-3475 8925)(-3475 9000);
WIRE 16 -1 (-3025 9000)(-3475 9000);
WIRE 16 -1 (-3025 9000)(-3025 8925);
WIRE 16 -1 (-2575 9000)(-3025 9000);
WIRE 16 -1 (-2575 8925)(-2575 9000);
WIRE 16 -1 (-2125 9000)(-2575 9000);
WIRE 16 -1 (-2125 8925)(-2125 9000);
WIRE 16 -1 (-1675 9000)(-2125 9000);
WIRE 16 -1 (-1675 9000)(-1675 8925);
WIRE 16 -1 (-1225 9000)(-1675 9000);
WIRE 16 -1 (-1225 8925)(-1225 9000);
WIRE 16 -1 (-1225 9000)(-775 9000);
WIRE 16 -1 (-775 8925)(-775 9000);
WIRE 16 -1 (-325 9000)(-775 9000);
WIRE 16 -1 (-325 8925)(-325 9000);
WIRE 16 -1 (125 9000)(-325 9000);
WIRE 16 -1 (125 9000)(125 8925);
WIRE 16 -1 (575 9000)(125 9000);
WIRE 16 -1 (575 8925)(575 9000);
WIRE 16 -1 (1025 9000)(575 9000);
WIRE 16 -1 (1025 8925)(1025 9000);
WIRE 16 -1 (1475 9000)(1025 9000);
WIRE 16 -1 (1475 9000)(1475 8925);
WIRE 16 -1 (1925 9000)(1475 9000);
WIRE 16 -1 (1925 8925)(1925 9000);
WIRE 16 -1 (-3475 6200)(-3475 6275);
WIRE 16 -1 (-3025 6275)(-3475 6275);
WIRE 16 -1 (-3025 6275)(-3025 6200);
WIRE 16 -1 (-2575 6275)(-3025 6275);
WIRE 16 -1 (-2575 6275)(-2575 6200);
WIRE 16 -1 (-2125 6275)(-2575 6275);
WIRE 16 -1 (-2125 6200)(-2125 6275);
WIRE 16 -1 (-1675 6275)(-2125 6275);
WIRE 16 -1 (-1675 6275)(-1675 6200);
WIRE 16 -1 (-3925 3800)(-3925 3925);
WIRE 16 -1 (-3475 3800)(-3925 3800);
WIRE 16 -1 (-3475 3800)(-3475 3925);
WIRE 16 -1 (-3025 3800)(-3475 3800);
WIRE 16 -1 (-3025 3800)(-3025 3925);
WIRE 16 -1 (-2575 3800)(-3025 3800);
WIRE 16 -1 (-2575 3800)(-2575 3925);
WIRE 16 -1 (-2125 3800)(-2575 3800);
WIRE 16 -1 (-2125 3800)(-2125 3925);
WIRE 16 -1 (-1675 3800)(-2125 3800);
WIRE 16 -1 (-1675 3800)(-1675 3925);
WIRE 16 -1 (-1225 3800)(-1675 3800);
WIRE 16 -1 (-1225 3800)(-1225 3925);
WIRE 16 -1 (-775 3800)(-1225 3800);
WIRE 16 -1 (-775 3800)(-775 3925);
WIRE 16 -1 (-325 3800)(-775 3800);
WIRE 16 -1 (-325 3800)(-325 3925);
WIRE 16 -1 (125 3800)(-325 3800);
WIRE 16 -1 (125 3800)(125 3925);
WIRE 16 -1 (575 3800)(125 3800);
WIRE 16 -1 (575 3800)(575 3925);
WIRE 16 -1 (1025 3800)(575 3800);
WIRE 16 -1 (1025 3800)(1025 3925);
WIRE 16 -1 (-3925 7725)(-3925 7850);
WIRE 16 -1 (-3475 7725)(-3925 7725);
WIRE 16 -1 (-3475 7850)(-3475 7725);
WIRE 16 -1 (-3025 7725)(-3475 7725);
WIRE 16 -1 (-3025 7725)(-3025 7850);
WIRE 16 -1 (-2575 7725)(-3025 7725);
WIRE 16 -1 (-2575 7725)(-2575 7850);
WIRE 16 -1 (-3475 8050)(-3475 8125);
WIRE 16 -1 (-3025 8125)(-3475 8125);
WIRE 16 -1 (-3025 8050)(-3025 8125);
WIRE 16 -1 (-2575 8125)(-3025 8125);
WIRE 16 -1 (-2575 8125)(-2575 8050);
WIRE 16 -1 (-3925 6875)(-3925 7000);
WIRE 16 -1 (-3475 6875)(-3925 6875);
WIRE 16 -1 (-3475 6875)(-3475 7000);
WIRE 16 -1 (-3075 6875)(-3475 6875);
WIRE 16 -1 (-3075 7000)(-3075 6875);
WIRE 16 -1 (-3475 7200)(-3475 7275);
WIRE 16 -1 (-3075 7275)(-3475 7275);
WIRE 16 -1 (-3075 7200)(-3075 7275);
DOT 1 (1925 8600);
DOT 1 (1475 9000);
DOT 1 (1475 8600);
DOT 1 (1025 9000);
DOT 1 (1025 8600);
DOT 1 (575 9000);
DOT 1 (575 8600);
DOT 1 (125 9000);
DOT 1 (-325 9000);
DOT 1 (125 8600);
DOT 1 (-325 8600);
DOT 1 (-775 9000);
DOT 1 (-775 8600);
DOT 1 (-1225 9000);
DOT 1 (-1225 8600);
DOT 1 (-1675 9000);
DOT 1 (-1675 8600);
DOT 1 (-2125 9000);
DOT 1 (-2125 8600);
DOT 1 (-2575 9000);
DOT 1 (-2575 8600);
DOT 1 (-2575 7725);
DOT 1 (-2575 6275);
DOT 1 (-2125 6275);
DOT 1 (1025 3800);
DOT 1 (575 4200);
DOT 1 (575 3800);
DOT 1 (125 4200);
DOT 1 (125 3800);
DOT 1 (-325 4200);
DOT 1 (-325 3800);
DOT 1 (-775 4200);
DOT 1 (-775 3800);
DOT 1 (-1675 5875);
DOT 1 (-2125 5875);
DOT 1 (-2575 5875);
DOT 1 (-2575 4850);
DOT 1 (-1225 4200);
DOT 1 (-1225 3800);
DOT 1 (-1675 4200);
DOT 1 (-1675 3800);
DOT 1 (-2125 4200);
DOT 1 (-2125 3800);
DOT 1 (-2575 4200);
DOT 1 (-2575 3800);
DOT 1 (-3025 9000);
DOT 1 (-3025 8600);
DOT 1 (-3475 9000);
DOT 1 (-3925 9000);
DOT 1 (-3475 8600);
DOT 1 (-3025 8125);
DOT 1 (-3025 7725);
DOT 1 (-3475 8125);
DOT 1 (-3925 8125);
DOT 1 (-3475 7725);
DOT 1 (-3075 6875);
DOT 1 (-3475 7275);
DOT 1 (-3475 6875);
DOT 1 (-3925 7275);
DOT 1 (-3925 6275);
DOT 1 (-3475 6275);
DOT 1 (-3025 6275);
DOT 1 (-3025 5875);
DOT 1 (-3475 5875);
DOT 1 (-3925 5250);
DOT 1 (-3025 5250);
DOT 1 (-3475 5250);
DOT 1 (-3025 4850);
DOT 1 (-3475 4850);
DOT 1 (-3025 4200);
DOT 1 (-3025 3800);
DOT 1 (-3475 4200);
DOT 1 (-3475 3800);
DOT 1 (-3925 4200);
FORCENOTE
PVCCFA_EHV: 6 MLCC CAPS PLACED AT CPU(UP>
(-3825 6325) 0;
DISPLAY LEFT (-3825 6325);
DISPLAY 0.808511 (-3825 6325);
PAINT SKYBLUE (-3825 6325);
FORCENOTE
PVCCFA_EHV: 6 0805 100UF MLCC CAPS PLACED AT CPU(RIGHT>
(-2811 4268) 0;
DISPLAY LEFT (-2811 4268);
DISPLAY 0.808511 (-2811 4268);
PAINT SKYBLUE (-2811 4268);
FORCENOTE
PVCCFA_EHV: 6 0805 100UF MLCC CAPS PLACED AT CPU(LEFT>
(-2811 4343) 0;
DISPLAY LEFT (-2811 4343);
DISPLAY 0.808511 (-2811 4343);
PAINT SKYBLUE (-2811 4343);
FORCENOTE
PVCCINFAON: 4 MLCC CAPS PLACED AT CPU(UP>
(-3825 5300) 0;
DISPLAY LEFT (-3825 5300);
DISPLAY 0.808511 (-3825 5300);
PAINT SKYBLUE (-3825 5300);
FORCENOTE
PVCCIN: 14 0805 100UF MLCC CAPS PLACED AT CPU(DOWN>
(-3825 9050) 0;
DISPLAY LEFT (-3825 9050);
DISPLAY 0.808511 (-3825 9050);
PAINT SKYBLUE (-3825 9050);
FORCENOTE
PVCCD_HV: 4 MLCC CAPS PLACED AT CPU(UP>
(-3825 8175) 0;
DISPLAY LEFT (-3825 8175);
DISPLAY 0.808511 (-3825 8175);
PAINT SKYBLUE (-3825 8175);
QUIT
